FILE_TYPE = MACRO_DRAWING;
SET COLOR_WIRE YELLOW;
SET COLOR_PROP ORANGE;
SET COLOR_DOT WHITE;
SET COLOR_ARC YELLOW;
SET COLOR_BODY GREEN;
SET COLOR_NOTE PURPLE;
SET PROP_DISPLAY VALUE;
SET PAGE_NUMBER P197;
FORCEADD UNIVERSAL_GND..1
(550 1325);
FORCEPROP 3 LASTPIN (550 1375) SIG_NAME GND\g
J 0
(560 1385);
DISPLAY 0.659574 (560 1385);
PAINT MONO (560 1385);
DISPLAY INVISIBLE (560 1385);
FORCEPROP 2 LAST CDS_LIB pure_quanta_power
J 0
(550 1325);
PAINT MONO (550 1325);
DISPLAY INVISIBLE (550 1325);
FORCEPROP 1 LAST PATH I1
J 0
(625 1325);
DISPLAY 0.872340 (625 1325);
PAINT AQUA (625 1325);
DISPLAY INVISIBLE (625 1325);
FORCEPROP 1 LAST HDL_POWER GND
J 1
(575 1250);
DISPLAY 0.872340 (575 1250);
PAINT GREEN (575 1250);
DISPLAY INVISIBLE (575 1250);
FORCEADD VCC_CORE..1
(4575 6050);
FORCEPROP 3 LASTPIN (4575 6000) SIG_NAME SW_P12V_STBY_PVDDIO_P1_FLT\g
J 0
(4585 6010);
DISPLAY 0.659574 (4585 6010);
PAINT MONO (4585 6010);
DISPLAY INVISIBLE (4585 6010);
FORCEPROP 1 LAST HDL_POWER SW_P12V_STBY_PVDDIO_P1_FLT
J 1
(4575 6100);
DISPLAY 0.489362 (4575 6100);
PAINT GREEN (4575 6100);
FORCEPROP 2 LAST CDS_LIB pure_quanta_power
J 0
(4575 6050);
DISPLAY INVISIBLE (4575 6050);
FORCEPROP 1 LAST PATH I100
J 0
(4625 6075);
DISPLAY 0.872340 (4625 6075);
PAINT AQUA (4625 6075);
DISPLAY INVISIBLE (4625 6075);
FORCEADD VCC_CORE..1
(5175 3350);
FORCEPROP 3 LASTPIN (5175 3300) SIG_NAME SW_P12V_STBY_PVDDIO_P1_FLT\g
J 0
(5185 3310);
DISPLAY 0.659574 (5185 3310);
PAINT MONO (5185 3310);
DISPLAY INVISIBLE (5185 3310);
FORCEPROP 1 LAST HDL_POWER SW_P12V_STBY_PVDDIO_P1_FLT
J 1
(5175 3400);
DISPLAY 0.489362 (5175 3400);
PAINT GREEN (5175 3400);
FORCEPROP 2 LAST CDS_LIB pure_quanta_power
J 0
(5175 3350);
DISPLAY INVISIBLE (5175 3350);
FORCEPROP 1 LAST PATH I101
J 0
(5225 3375);
DISPLAY 0.872340 (5225 3375);
PAINT AQUA (5225 3375);
DISPLAY INVISIBLE (5225 3375);
FORCEADD Q_CAP..1
(25 4425);
FORCEPROP 1 LAST LOCATION PC435_7
J 0
(75 4525);
DISPLAY 0.489362 (75 4525);
PAINT SKYBLUE (75 4525);
FORCEPROP 2 LAST $SEC 1
J 0
(75 4625);
DISPLAY 0.680851 (75 4625);
PAINT MONO (75 4625);
DISPLAY INVISIBLE (75 4625);
FORCEPROP 0 LAST CDS_SEC 1
J 0
(275 4475);
DISPLAY 1.021277 (275 4475);
DISPLAY INVISIBLE (275 4475);
FORCEPROP 1 LASTPIN (25 4525) $PN 1
J 0
(35 4505);
DISPLAY 0.489362 (35 4505);
PAINT MONO (35 4505);
FORCEPROP 1 LASTPIN (25 4325) $PN 2
J 0
(35 4305);
DISPLAY 0.489362 (35 4305);
PAINT MONO (35 4305);
FORCEPROP 1 LAST MATERIAL X7R
J 0
(75 4325);
DISPLAY 0.489362 (75 4325);
PAINT SKYBLUE (75 4325);
FORCEPROP 1 LAST TOLERANCE 10%
J 0
(75 4375);
DISPLAY 0.489362 (75 4375);
PAINT SKYBLUE (75 4375);
FORCEPROP 1 LAST VALUE 0.1UF
J 0
(75 4475);
DISPLAY 0.489362 (75 4475);
PAINT SKYBLUE (75 4475);
FORCEPROP 1 LAST PART_NUMBER CH4104K1B00
J 0
(75 4275);
DISPLAY 0.489362 (75 4275);
PAINT SKYBLUE (75 4275);
FORCEPROP 1 LAST VOLTAGE 25V
J 0
(75 4425);
DISPLAY 0.489362 (75 4425);
PAINT SKYBLUE (75 4425);
FORCEPROP 1 LAST PACK_TYPE 0402
J 0
(75 4225);
DISPLAY 0.489362 (75 4225);
PAINT SKYBLUE (75 4225);
FORCEPROP 2 LAST CDS_LIB pure_quanta
J 0
(25 4425);
DISPLAY INVISIBLE (25 4425);
FORCEPROP 1 LAST PATH I105
J 0
(75 4575);
DISPLAY 0.978723 (75 4575);
PAINT WHITE (75 4575);
DISPLAY INVISIBLE (75 4575);
FORCEADD Q_CAP..1
(25 1675);
FORCEPROP 1 LAST LOCATION PC436_8
J 0
(75 1775);
DISPLAY 0.489362 (75 1775);
PAINT SKYBLUE (75 1775);
FORCEPROP 2 LAST $SEC 1
J 0
(75 1875);
DISPLAY 0.680851 (75 1875);
PAINT MONO (75 1875);
DISPLAY INVISIBLE (75 1875);
FORCEPROP 0 LAST CDS_SEC 1
J 0
(275 1725);
DISPLAY 1.021277 (275 1725);
DISPLAY INVISIBLE (275 1725);
FORCEPROP 1 LASTPIN (25 1775) $PN 1
J 0
(35 1755);
DISPLAY 0.489362 (35 1755);
PAINT MONO (35 1755);
FORCEPROP 1 LASTPIN (25 1575) $PN 2
J 0
(35 1555);
DISPLAY 0.489362 (35 1555);
PAINT MONO (35 1555);
FORCEPROP 1 LAST VALUE 0.1UF
J 0
(75 1725);
DISPLAY 0.489362 (75 1725);
PAINT SKYBLUE (75 1725);
FORCEPROP 1 LAST VOLTAGE 25V
J 0
(75 1675);
DISPLAY 0.489362 (75 1675);
PAINT SKYBLUE (75 1675);
FORCEPROP 1 LAST TOLERANCE 10%
J 0
(75 1625);
DISPLAY 0.489362 (75 1625);
PAINT SKYBLUE (75 1625);
FORCEPROP 1 LAST MATERIAL X7R
J 0
(75 1575);
DISPLAY 0.489362 (75 1575);
PAINT SKYBLUE (75 1575);
FORCEPROP 1 LAST PART_NUMBER CH4104K1B00
J 0
(75 1525);
DISPLAY 0.489362 (75 1525);
PAINT SKYBLUE (75 1525);
FORCEPROP 1 LAST PACK_TYPE 0402
J 0
(75 1475);
DISPLAY 0.489362 (75 1475);
PAINT SKYBLUE (75 1475);
FORCEPROP 2 LAST CDS_LIB pure_quanta
J 0
(25 1675);
DISPLAY INVISIBLE (25 1675);
FORCEPROP 1 LAST PATH I106
J 0
(75 1825);
DISPLAY 0.978723 (75 1825);
PAINT WHITE (75 1825);
DISPLAY INVISIBLE (75 1825);
FORCEADD Q_RES..1
(4925 1025);
FORCEPROP 1 LAST LOCATION PR281
J 0
(4875 1050);
DISPLAY 0.489362 (4875 1050);
PAINT SKYBLUE (4875 1050);
FORCEPROP 0 LAST $SEC 1
J 0
(5175 1150);
DISPLAY 0.680851 (5175 1150);
PAINT MONO (5175 1150);
DISPLAY INVISIBLE (5175 1150);
FORCEPROP 0 LAST CDS_SEC 1
J 0
(5175 1150);
DISPLAY 1.021277 (5175 1150);
DISPLAY INVISIBLE (5175 1150);
FORCEPROP 1 LASTPIN (4825 1025) $PN 1
J 0
(4837 1037);
DISPLAY 0.787234 (4837 1037);
PAINT MONO (4837 1037);
DISPLAY INVISIBLE (4837 1037);
FORCEPROP 1 LASTPIN (5025 1025) $PN 2
J 0
(4987 1037);
DISPLAY 0.787234 (4987 1037);
PAINT MONO (4987 1037);
DISPLAY INVISIBLE (4987 1037);
FORCEPROP 1 LAST WATTAGE 1/16W
J 2
(5150 1100);
DISPLAY 0.489362 (5150 1100);
PAINT SKYBLUE (5150 1100);
FORCEPROP 1 LAST MATERIAL CHIP
J 0
(5050 1050);
DISPLAY 0.489362 (5050 1050);
PAINT SKYBLUE (5050 1050);
FORCEPROP 1 LAST TOLERANCE 5%
J 0
(4750 1075);
DISPLAY 0.489362 (4750 1075);
PAINT SKYBLUE (4750 1075);
FORCEPROP 1 LAST VALUE 0
J 2
(4725 1075);
DISPLAY 0.489362 (4725 1075);
PAINT SKYBLUE (4725 1075);
FORCEPROP 1 LAST PART_NUMBER CS00002JB38
J 0
(4625 975);
DISPLAY 0.489362 (4625 975);
PAINT SKYBLUE (4625 975);
FORCEPROP 1 LAST PACK_TYPE 0402LF
J 0
(5025 975);
DISPLAY 0.489362 (5025 975);
PAINT SKYBLUE (5025 975);
FORCEPROP 2 LAST CDS_LIB pure_quanta
J 0
(4925 1025);
DISPLAY INVISIBLE (4925 1025);
FORCEPROP 1 LAST PATH I107
J 0
(4875 1175);
DISPLAY 0.978723 (4875 1175);
PAINT WHITE (4875 1175);
DISPLAY INVISIBLE (4875 1175);
FORCEADD Q_RES..1
(5100 3800);
FORCEPROP 1 LAST LOCATION PR280
J 0
(5050 3850);
DISPLAY 0.489362 (5050 3850);
PAINT SKYBLUE (5050 3850);
FORCEPROP 0 LAST $SEC 1
J 0
(5350 3925);
DISPLAY 0.680851 (5350 3925);
PAINT MONO (5350 3925);
DISPLAY INVISIBLE (5350 3925);
FORCEPROP 0 LAST CDS_SEC 1
J 0
(5350 3925);
DISPLAY 1.021277 (5350 3925);
DISPLAY INVISIBLE (5350 3925);
FORCEPROP 1 LASTPIN (5000 3800) $PN 1
J 0
(5012 3812);
DISPLAY 0.787234 (5012 3812);
PAINT MONO (5012 3812);
DISPLAY INVISIBLE (5012 3812);
FORCEPROP 1 LASTPIN (5200 3800) $PN 2
J 0
(5162 3812);
DISPLAY 0.787234 (5162 3812);
PAINT MONO (5162 3812);
DISPLAY INVISIBLE (5162 3812);
FORCEPROP 1 LAST TOLERANCE 5%
J 0
(4900 3850);
DISPLAY 0.489362 (4900 3850);
PAINT SKYBLUE (4900 3850);
FORCEPROP 1 LAST VALUE 0
J 2
(4875 3850);
DISPLAY 0.489362 (4875 3850);
PAINT SKYBLUE (4875 3850);
FORCEPROP 1 LAST WATTAGE 1/16W
J 2
(5325 3875);
DISPLAY 0.489362 (5325 3875);
PAINT SKYBLUE (5325 3875);
FORCEPROP 1 LAST MATERIAL CHIP
J 0
(5225 3825);
DISPLAY 0.489362 (5225 3825);
PAINT SKYBLUE (5225 3825);
FORCEPROP 1 LAST PART_NUMBER CS00002JB38
J 0
(4775 3750);
DISPLAY 0.489362 (4775 3750);
PAINT SKYBLUE (4775 3750);
FORCEPROP 1 LAST PACK_TYPE 0402LF
J 0
(5200 3750);
DISPLAY 0.489362 (5200 3750);
PAINT SKYBLUE (5200 3750);
FORCEPROP 2 LAST CDS_LIB pure_quanta
J 0
(5100 3800);
DISPLAY INVISIBLE (5100 3800);
FORCEPROP 1 LAST PATH I108
J 0
(5050 3950);
DISPLAY 0.978723 (5050 3950);
PAINT WHITE (5050 3950);
DISPLAY INVISIBLE (5050 3950);
FORCEADD Q_CAP..1
(4925 5025);
FORCEPROP 1 LAST LOCATION PC447
J 0
(4975 5125);
DISPLAY 0.489362 (4975 5125);
PAINT SKYBLUE (4975 5125);
FORCEPROP 0 LAST $SEC 1
J 0
(4975 5175);
DISPLAY 0.680851 (4975 5175);
PAINT MONO (4975 5175);
DISPLAY INVISIBLE (4975 5175);
FORCEPROP 0 LAST CDS_SEC 1
J 2
(4975 5150);
DISPLAY 1.021277 (4975 5150);
DISPLAY INVISIBLE (4975 5150);
FORCEPROP 1 LASTPIN (4925 5125) $PN 1
J 0
(4935 5105);
DISPLAY 0.489362 (4935 5105);
PAINT MONO (4935 5105);
FORCEPROP 1 LASTPIN (4925 4925) $PN 2
J 0
(4935 4905);
DISPLAY 0.489362 (4935 4905);
PAINT MONO (4935 4905);
FORCEPROP 1 LAST PART_NUMBER CH4223K1B00
J 0
(4975 4875);
DISPLAY 0.489362 (4975 4875);
PAINT SKYBLUE (4975 4875);
FORCEPROP 1 LAST MATERIAL X7R
J 0
(4975 4925);
DISPLAY 0.489362 (4975 4925);
PAINT SKYBLUE (4975 4925);
FORCEPROP 1 LAST TOLERANCE 10%
J 0
(4975 4975);
DISPLAY 0.489362 (4975 4975);
PAINT SKYBLUE (4975 4975);
FORCEPROP 1 LAST VALUE 0.22UF
J 0
(4975 5075);
DISPLAY 0.489362 (4975 5075);
PAINT SKYBLUE (4975 5075);
FORCEPROP 1 LAST VOLTAGE 16V
J 0
(4975 5025);
DISPLAY 0.489362 (4975 5025);
PAINT SKYBLUE (4975 5025);
FORCEPROP 1 LAST PACK_TYPE 0402
J 0
(4975 4825);
DISPLAY 0.489362 (4975 4825);
PAINT SKYBLUE (4975 4825);
FORCEPROP 2 LAST CDS_LIB pure_quanta
J 2
(4925 5025);
DISPLAY INVISIBLE (4925 5025);
FORCEPROP 1 LAST PATH I109
J 0
(4975 5175);
DISPLAY 0.978723 (4975 5175);
PAINT WHITE (4975 5175);
DISPLAY INVISIBLE (4975 5175);
FORCEADD Q_CAP..1
(4575 2275);
FORCEPROP 1 LAST LOCATION PC445
J 0
(4625 2375);
DISPLAY 0.489362 (4625 2375);
PAINT SKYBLUE (4625 2375);
FORCEPROP 0 LAST $SEC 1
J 0
(4625 2425);
DISPLAY 0.680851 (4625 2425);
PAINT MONO (4625 2425);
DISPLAY INVISIBLE (4625 2425);
FORCEPROP 0 LAST CDS_SEC 1
J 2
(4625 2400);
DISPLAY 1.021277 (4625 2400);
DISPLAY INVISIBLE (4625 2400);
FORCEPROP 1 LASTPIN (4575 2375) $PN 1
J 0
(4585 2355);
DISPLAY 0.489362 (4585 2355);
PAINT MONO (4585 2355);
FORCEPROP 1 LASTPIN (4575 2175) $PN 2
J 0
(4585 2155);
DISPLAY 0.489362 (4585 2155);
PAINT MONO (4585 2155);
FORCEPROP 1 LAST MATERIAL X7R
J 0
(4625 2175);
DISPLAY 0.489362 (4625 2175);
PAINT SKYBLUE (4625 2175);
FORCEPROP 1 LAST TOLERANCE 10%
J 0
(4625 2225);
DISPLAY 0.489362 (4625 2225);
PAINT SKYBLUE (4625 2225);
FORCEPROP 1 LAST VALUE 0.22UF
J 0
(4625 2325);
DISPLAY 0.489362 (4625 2325);
PAINT SKYBLUE (4625 2325);
FORCEPROP 1 LAST PART_NUMBER CH4223K1B00
J 0
(4625 2125);
DISPLAY 0.489362 (4625 2125);
PAINT SKYBLUE (4625 2125);
FORCEPROP 1 LAST VOLTAGE 16V
J 0
(4625 2275);
DISPLAY 0.489362 (4625 2275);
PAINT SKYBLUE (4625 2275);
FORCEPROP 1 LAST PACK_TYPE 0402
J 0
(4625 2075);
DISPLAY 0.489362 (4625 2075);
PAINT SKYBLUE (4625 2075);
FORCEPROP 2 LAST CDS_LIB pure_quanta
J 2
(4575 2275);
DISPLAY INVISIBLE (4575 2275);
FORCEPROP 1 LAST PATH I110
J 0
(4625 2425);
DISPLAY 0.978723 (4625 2425);
PAINT WHITE (4625 2425);
DISPLAY INVISIBLE (4625 2425);
FORCEADD Q_INDUCTOR4P_14..1
(5950 1925);
FORCEPROP 1 LAST LOCATION PL48
J 0
(5625 2100);
DISPLAY 0.489362 (5625 2100);
PAINT SKYBLUE (5625 2100);
FORCEPROP 0 LAST $SEC 1
J 0
(6000 2125);
DISPLAY 0.680851 (6000 2125);
PAINT MONO (6000 2125);
DISPLAY INVISIBLE (6000 2125);
FORCEPROP 0 LAST CDS_SEC 1
J 0
(6000 2125);
DISPLAY 1.021277 (6000 2125);
DISPLAY INVISIBLE (6000 2125);
FORCEPROP 0 LASTPIN (5550 2050) $PN 1
J 2
(5540 2060);
DISPLAY 0.489362 (5540 2060);
PAINT MONO (5540 2060);
FORCEPROP 0 LASTPIN (5550 1800) $PN 2
J 2
(5540 1810);
DISPLAY 0.489362 (5540 1810);
PAINT MONO (5540 1810);
FORCEPROP 0 LASTPIN (6350 1800) $PN 3
J 0
(6360 1810);
DISPLAY 0.489362 (6360 1810);
PAINT MONO (6360 1810);
FORCEPROP 0 LASTPIN (6350 2050) $PN 4
J 0
(6360 2060);
DISPLAY 0.489362 (6360 2060);
PAINT MONO (6360 2060);
FORCEPROP 2 LAST PART_TYPE SMLF
J 0
(5875 1675);
DISPLAY 1.021277 (5875 1675);
FORCEPROP 1 LAST MATERIAL IND
J 0
(5750 2100);
DISPLAY 0.489362 (5750 2100);
PAINT SKYBLUE (5750 2100);
FORCEPROP 2 LAST VALUE 150NH
J 0
(5850 2100);
DISPLAY 0.489362 (5850 2100);
PAINT SKYBLUE (5850 2100);
FORCEPROP 1 LAST PART_NUMBER CV+15^0TZ04
J 0
(6000 2100);
DISPLAY 0.489362 (6000 2100);
PAINT SKYBLUE (6000 2100);
FORCEPROP 2 LAST CDS_LIB pure_quanta
J 0
(5950 1925);
DISPLAY INVISIBLE (5950 1925);
FORCEPROP 1 LAST NEEDS_NO_SIZE TRUE
J 0
(5950 1925);
DISPLAY 0.468085 (5950 1925);
PAINT GREEN (5950 1925);
DISPLAY INVISIBLE (5950 1925);
FORCEPROP 1 LAST PATH I111
J 0
(6150 2080);
DISPLAY 0.723404 (6150 2080);
PAINT GREEN (6150 2080);
DISPLAY INVISIBLE (6150 2080);
FORCEADD Q_INDUCTOR4P_14..1
(5775 4675);
FORCEPROP 1 LAST LOCATION PL47
J 0
(5500 4850);
DISPLAY 0.489362 (5500 4850);
PAINT SKYBLUE (5500 4850);
FORCEPROP 0 LAST $SEC 1
J 0
(5825 4875);
DISPLAY 0.680851 (5825 4875);
PAINT MONO (5825 4875);
DISPLAY INVISIBLE (5825 4875);
FORCEPROP 0 LAST CDS_SEC 1
J 0
(5825 4875);
DISPLAY 1.021277 (5825 4875);
DISPLAY INVISIBLE (5825 4875);
FORCEPROP 0 LASTPIN (5375 4800) $PN 1
J 2
(5365 4810);
DISPLAY 0.489362 (5365 4810);
PAINT MONO (5365 4810);
FORCEPROP 0 LASTPIN (5375 4550) $PN 2
J 2
(5365 4560);
DISPLAY 0.489362 (5365 4560);
PAINT MONO (5365 4560);
FORCEPROP 0 LASTPIN (6175 4550) $PN 3
J 0
(6185 4560);
DISPLAY 0.489362 (6185 4560);
PAINT MONO (6185 4560);
FORCEPROP 0 LASTPIN (6175 4800) $PN 4
J 0
(6185 4810);
DISPLAY 0.489362 (6185 4810);
PAINT MONO (6185 4810);
FORCEPROP 1 LAST MATERIAL IND
J 0
(5575 4850);
DISPLAY 0.489362 (5575 4850);
PAINT SKYBLUE (5575 4850);
FORCEPROP 2 LAST PART_TYPE SMLF
J 0
(5700 4425);
DISPLAY 1.021277 (5700 4425);
FORCEPROP 2 LAST VALUE 150NH
J 0
(5675 4850);
DISPLAY 0.489362 (5675 4850);
PAINT SKYBLUE (5675 4850);
FORCEPROP 1 LAST PART_NUMBER CV+15^0TZ04
J 0
(5825 4850);
DISPLAY 0.489362 (5825 4850);
PAINT SKYBLUE (5825 4850);
FORCEPROP 2 LAST CDS_LIB pure_quanta
J 0
(5775 4675);
DISPLAY INVISIBLE (5775 4675);
FORCEPROP 1 LAST NEEDS_NO_SIZE TRUE
J 0
(5775 4675);
DISPLAY 0.468085 (5775 4675);
PAINT GREEN (5775 4675);
DISPLAY INVISIBLE (5775 4675);
FORCEPROP 1 LAST PATH I112
J 0
(5975 4830);
DISPLAY 0.723404 (5975 4830);
PAINT GREEN (5975 4830);
DISPLAY INVISIBLE (5975 4830);
FORCEADD Q_RES..1
(3850 2400);
FORCEPROP 1 LAST LOCATION PR278
J 0
(3800 2450);
DISPLAY 0.489362 (3800 2450);
PAINT SKYBLUE (3800 2450);
FORCEPROP 0 LAST $SEC 1
J 0
(4025 2475);
DISPLAY 0.680851 (4025 2475);
PAINT MONO (4025 2475);
DISPLAY INVISIBLE (4025 2475);
FORCEPROP 0 LAST CDS_SEC 1
J 0
(4025 2475);
DISPLAY 1.021277 (4025 2475);
DISPLAY INVISIBLE (4025 2475);
FORCEPROP 1 LASTPIN (3750 2400) $PN 1
J 0
(3762 2412);
DISPLAY 0.787234 (3762 2412);
PAINT MONO (3762 2412);
DISPLAY INVISIBLE (3762 2412);
FORCEPROP 1 LASTPIN (3950 2400) $PN 2
J 0
(3912 2412);
DISPLAY 0.787234 (3912 2412);
PAINT MONO (3912 2412);
DISPLAY INVISIBLE (3912 2412);
FORCEPROP 1 LAST PACK_TYPE 0402LF
J 0
(3950 2300);
DISPLAY 0.489362 (3950 2300);
PAINT SKYBLUE (3950 2300);
FORCEPROP 1 LAST TOLERANCE 1%
J 0
(3675 2300);
DISPLAY 0.489362 (3675 2300);
PAINT SKYBLUE (3675 2300);
FORCEPROP 1 LAST MATERIAL CHIP
J 0
(3950 2350);
DISPLAY 0.489362 (3950 2350);
PAINT SKYBLUE (3950 2350);
FORCEPROP 1 LAST WATTAGE 1/16W
J 2
(4075 2425);
DISPLAY 0.489362 (4075 2425);
PAINT SKYBLUE (4075 2425);
FORCEPROP 1 LAST VALUE 4.7
J 2
(3750 2425);
DISPLAY 0.489362 (3750 2425);
PAINT SKYBLUE (3750 2425);
FORCEPROP 1 LAST PART_NUMBER CS-4702FB19
J 0
(3550 2350);
DISPLAY 0.489362 (3550 2350);
PAINT SKYBLUE (3550 2350);
FORCEPROP 1 LAST PATH I113
J 0
(3800 2550);
DISPLAY 0.978723 (3800 2550);
PAINT WHITE (3800 2550);
DISPLAY INVISIBLE (3800 2550);
FORCEPROP 2 LAST CDS_LIB pure_quanta
J 0
(3850 2400);
DISPLAY INVISIBLE (3850 2400);
FORCEADD Q_CAPP..1
(5000 5725);
FORCEPROP 1 LAST LOCATION PC454
J 0
(5050 5850);
DISPLAY 0.489362 (5050 5850);
PAINT SKYBLUE (5050 5850);
FORCEPROP 0 LAST $SEC 1
J 0
(5050 5850);
DISPLAY 0.680851 (5050 5850);
PAINT MONO (5050 5850);
DISPLAY INVISIBLE (5050 5850);
FORCEPROP 0 LAST CDS_SEC 1
J 0
(5050 5850);
DISPLAY 1.021277 (5050 5850);
DISPLAY INVISIBLE (5050 5850);
FORCEPROP 1 LASTPIN (5000 5825) $PN 1
J 0
(5010 5810);
DISPLAY 0.489362 (5010 5810);
PAINT MONO (5010 5810);
FORCEPROP 1 LASTPIN (5000 5625) $PN 2
J 0
(5010 5610);
DISPLAY 0.489362 (5010 5610);
PAINT MONO (5010 5610);
FORCEPROP 1 LAST MATERIAL OSCON
J 0
(5050 5650);
DISPLAY 0.489362 (5050 5650);
PAINT SKYBLUE (5050 5650);
FORCEPROP 1 LAST TOLERANCE 20%
J 0
(5050 5750);
DISPLAY 0.489362 (5050 5750);
PAINT SKYBLUE (5050 5750);
FORCEPROP 1 LAST VALUE 220UF
J 0
(5050 5800);
DISPLAY 0.489362 (5050 5800);
PAINT SKYBLUE (5050 5800);
FORCEPROP 1 LAST PART_NUMBER SP_CC72204MD02
J 0
(5050 5550);
DISPLAY 0.489362 (5050 5550);
PAINT SKYBLUE (5050 5550);
FORCEPROP 1 LAST VOLTAGE 25V
J 0
(5050 5700);
DISPLAY 0.489362 (5050 5700);
PAINT SKYBLUE (5050 5700);
FORCEPROP 1 LAST PACK_TYPE THLF
J 0
(5050 5600);
DISPLAY 0.489362 (5050 5600);
PAINT SKYBLUE (5050 5600);
FORCEPROP 2 LAST CDS_LIB pure_quanta
J 0
(5000 5725);
DISPLAY INVISIBLE (5000 5725);
FORCEPROP 1 LAST PATH I115
J 0
(5050 5875);
DISPLAY 0.978723 (5050 5875);
DISPLAY INVISIBLE (5050 5875);
FORCEADD OFFPAGE..5
(1050 4300);
FORCEPROP 2 LAST $XR2 193 
J 0
(765 4336);
DISPLAY 0.638298 (765 4336);
PAINT MONO (765 4336);
FORCEPROP 2 LAST $XR1 199 
J 0
(765 4264);
DISPLAY 0.638298 (765 4264);
PAINT MONO (765 4264);
FORCEPROP 2 LAST $XR0 198 
J 0
(765 4300);
DISPLAY 0.638298 (765 4300);
PAINT MONO (765 4300);
FORCEPROP 2 LAST PATH I116
J 0
(1100 4375);
DISPLAY 1.021277 (1100 4375);
DISPLAY INVISIBLE (1100 4375);
FORCEPROP 1 LAST COMMENT_BODY TRUE
J 0
(1150 4225);
DISPLAY 0.872340 (1150 4225);
PAINT GREEN (1150 4225);
DISPLAY INVISIBLE (1150 4225);
FORCEPROP 1 LAST OFFPAGE TRUE
J 0
(1375 4175);
DISPLAY 0.872340 (1375 4175);
PAINT GREEN (1375 4175);
DISPLAY INVISIBLE (1375 4175);
FORCEPROP 2 LAST CDS_LIB standard
J 0
(1050 4300);
DISPLAY INVISIBLE (1050 4300);
FORCEADD OFFPAGE..5
(1025 1550);
FORCEPROP 2 LAST $XR2 193 
J 0
(770 1586);
DISPLAY 0.638298 (770 1586);
PAINT MONO (770 1586);
FORCEPROP 2 LAST $XR1 199 
J 0
(770 1514);
DISPLAY 0.638298 (770 1514);
PAINT MONO (770 1514);
FORCEPROP 2 LAST $XR0 198 
J 0
(770 1550);
DISPLAY 0.638298 (770 1550);
PAINT MONO (770 1550);
FORCEPROP 2 LAST CDS_LIB standard
J 0
(1025 1550);
DISPLAY INVISIBLE (1025 1550);
FORCEPROP 1 LAST OFFPAGE TRUE
J 0
(1350 1425);
DISPLAY 0.872340 (1350 1425);
PAINT GREEN (1350 1425);
DISPLAY INVISIBLE (1350 1425);
FORCEPROP 1 LAST COMMENT_BODY TRUE
J 0
(1125 1475);
DISPLAY 0.872340 (1125 1475);
PAINT GREEN (1125 1475);
DISPLAY INVISIBLE (1125 1475);
FORCEPROP 2 LAST PATH I117
J 0
(1075 1625);
DISPLAY 1.021277 (1075 1625);
DISPLAY INVISIBLE (1075 1625);
FORCEADD Q_CAPP..1
(6925 3075);
FORCEPROP 1 LAST LOCATION PC450
J 0
(6975 3225);
DISPLAY 0.489362 (6975 3225);
PAINT SKYBLUE (6975 3225);
FORCEPROP 0 LAST $SEC 1
J 0
(6975 3250);
DISPLAY 0.680851 (6975 3250);
PAINT MONO (6975 3250);
DISPLAY INVISIBLE (6975 3250);
FORCEPROP 0 LAST CDS_SEC 1
J 0
(6975 3250);
DISPLAY 1.021277 (6975 3250);
DISPLAY INVISIBLE (6975 3250);
FORCEPROP 1 LASTPIN (6925 3175) $PN 1
J 0
(6935 3160);
DISPLAY 0.489362 (6935 3160);
PAINT MONO (6935 3160);
FORCEPROP 1 LASTPIN (6925 2975) $PN 2
J 0
(6935 2960);
DISPLAY 0.489362 (6935 2960);
PAINT MONO (6935 2960);
FORCEPROP 1 LAST PART_NUMBER CH747LM8825
J 0
(6975 2925);
DISPLAY 0.489362 (6975 2925);
PAINT SKYBLUE (6975 2925);
FORCEPROP 1 LAST MATERIAL SPCAP
J 0
(6975 3025);
DISPLAY 0.489362 (6975 3025);
PAINT SKYBLUE (6975 3025);
FORCEPROP 1 LAST TOLERANCE 20%
J 0
(6975 3125);
DISPLAY 0.489362 (6975 3125);
PAINT SKYBLUE (6975 3125);
FORCEPROP 1 LAST VALUE 470UF
J 0
(6975 3175);
DISPLAY 0.489362 (6975 3175);
PAINT SKYBLUE (6975 3175);
FORCEPROP 1 LAST VOLTAGE 2.5V
J 0
(6975 3075);
DISPLAY 0.489362 (6975 3075);
PAINT SKYBLUE (6975 3075);
FORCEPROP 1 LAST PACK_TYPE SMLF
J 0
(6975 2975);
DISPLAY 0.489362 (6975 2975);
PAINT SKYBLUE (6975 2975);
FORCEPROP 2 LAST CDS_LIB pure_quanta
J 0
(6925 3075);
DISPLAY INVISIBLE (6925 3075);
FORCEPROP 1 LAST PATH I118
J 0
(6975 3225);
DISPLAY 0.978723 (6975 3225);
DISPLAY INVISIBLE (6975 3225);
FORCEADD Q_CAP..1
(3325 5700);
FORCEPROP 1 LAST LOCATION PC438_1
J 0
(3375 5850);
DISPLAY 0.489362 (3375 5850);
PAINT SKYBLUE (3375 5850);
FORCEPROP 0 LAST $SEC 1
J 0
(3375 5850);
DISPLAY 0.680851 (3375 5850);
PAINT MONO (3375 5850);
DISPLAY INVISIBLE (3375 5850);
FORCEPROP 0 LAST CDS_SEC 1
J 0
(3375 5850);
DISPLAY 1.021277 (3375 5850);
DISPLAY INVISIBLE (3375 5850);
FORCEPROP 1 LASTPIN (3325 5800) $PN 1
J 0
(3335 5780);
DISPLAY 0.489362 (3335 5780);
PAINT MONO (3335 5780);
FORCEPROP 1 LASTPIN (3325 5600) $PN 2
J 0
(3335 5580);
DISPLAY 0.489362 (3335 5580);
PAINT MONO (3335 5580);
FORCEPROP 1 LAST MATERIAL X7R
J 0
(3375 5650);
DISPLAY 0.489362 (3375 5650);
PAINT SKYBLUE (3375 5650);
FORCEPROP 1 LAST TOLERANCE 10%
J 0
(3375 5700);
DISPLAY 0.489362 (3375 5700);
PAINT SKYBLUE (3375 5700);
FORCEPROP 1 LAST VALUE 0.1UF
J 0
(3375 5800);
DISPLAY 0.489362 (3375 5800);
PAINT SKYBLUE (3375 5800);
FORCEPROP 1 LAST PART_NUMBER CH4104K1B00
J 0
(3375 5600);
DISPLAY 0.489362 (3375 5600);
PAINT SKYBLUE (3375 5600);
FORCEPROP 1 LAST VOLTAGE 25V
J 0
(3375 5750);
DISPLAY 0.489362 (3375 5750);
PAINT SKYBLUE (3375 5750);
FORCEPROP 1 LAST PACK_TYPE 0402
J 0
(3375 5550);
DISPLAY 0.489362 (3375 5550);
PAINT SKYBLUE (3375 5550);
FORCEPROP 2 LAST CDS_LIB pure_quanta
J 0
(3325 5700);
DISPLAY INVISIBLE (3325 5700);
FORCEPROP 1 LAST PATH I119
J 0
(3375 5850);
DISPLAY 0.978723 (3375 5850);
PAINT WHITE (3375 5850);
DISPLAY INVISIBLE (3375 5850);
FORCEADD Q_CAP..1
(3400 2975);
FORCEPROP 1 LAST LOCATION PC439_2
J 0
(3450 3075);
DISPLAY 0.489362 (3450 3075);
PAINT SKYBLUE (3450 3075);
FORCEPROP 0 LAST $SEC 1
J 0
(3450 3125);
DISPLAY 0.680851 (3450 3125);
PAINT MONO (3450 3125);
DISPLAY INVISIBLE (3450 3125);
FORCEPROP 0 LAST CDS_SEC 1
J 0
(3450 3125);
DISPLAY 1.021277 (3450 3125);
DISPLAY INVISIBLE (3450 3125);
FORCEPROP 1 LASTPIN (3400 3075) $PN 1
J 0
(3410 3055);
DISPLAY 0.489362 (3410 3055);
PAINT MONO (3410 3055);
FORCEPROP 1 LASTPIN (3400 2875) $PN 2
J 0
(3410 2855);
DISPLAY 0.489362 (3410 2855);
PAINT MONO (3410 2855);
FORCEPROP 1 LAST MATERIAL X7R
J 0
(3450 2875);
DISPLAY 0.489362 (3450 2875);
PAINT SKYBLUE (3450 2875);
FORCEPROP 1 LAST TOLERANCE 10%
J 0
(3450 2925);
DISPLAY 0.489362 (3450 2925);
PAINT SKYBLUE (3450 2925);
FORCEPROP 1 LAST VALUE 0.1UF
J 0
(3450 3025);
DISPLAY 0.489362 (3450 3025);
PAINT SKYBLUE (3450 3025);
FORCEPROP 1 LAST PART_NUMBER CH4104K1B00
J 0
(3450 2825);
DISPLAY 0.489362 (3450 2825);
PAINT SKYBLUE (3450 2825);
FORCEPROP 1 LAST VOLTAGE 25V
J 0
(3450 2975);
DISPLAY 0.489362 (3450 2975);
PAINT SKYBLUE (3450 2975);
FORCEPROP 1 LAST PACK_TYPE 0402
J 0
(3450 2775);
DISPLAY 0.489362 (3450 2775);
PAINT SKYBLUE (3450 2775);
FORCEPROP 2 LAST CDS_LIB pure_quanta
J 0
(3400 2975);
DISPLAY INVISIBLE (3400 2975);
FORCEPROP 1 LAST PATH I120
J 0
(3450 3125);
DISPLAY 0.978723 (3450 3125);
PAINT WHITE (3450 3125);
DISPLAY INVISIBLE (3450 3125);
FORCEADD Q_CAP..1
(1000 5075);
FORCEPROP 1 LAST LOCATION PC433
J 0
(1050 5175);
DISPLAY 0.489362 (1050 5175);
PAINT SKYBLUE (1050 5175);
FORCEPROP 0 LAST $SEC 1
J 0
(1050 5225);
DISPLAY 0.680851 (1050 5225);
PAINT MONO (1050 5225);
DISPLAY INVISIBLE (1050 5225);
FORCEPROP 0 LAST CDS_SEC 1
J 0
(1050 5225);
DISPLAY 1.021277 (1050 5225);
DISPLAY INVISIBLE (1050 5225);
FORCEPROP 1 LASTPIN (1000 5175) $PN 1
J 0
(1010 5155);
DISPLAY 0.489362 (1010 5155);
PAINT MONO (1010 5155);
FORCEPROP 1 LASTPIN (1000 4975) $PN 2
J 0
(1010 4955);
DISPLAY 0.489362 (1010 4955);
PAINT MONO (1010 4955);
FORCEPROP 1 LAST MATERIAL X6S
J 0
(1050 4975);
DISPLAY 0.489362 (1050 4975);
PAINT SKYBLUE (1050 4975);
FORCEPROP 1 LAST TOLERANCE 10%
J 0
(1050 5025);
DISPLAY 0.489362 (1050 5025);
PAINT SKYBLUE (1050 5025);
FORCEPROP 1 LAST VALUE 2.2UF
J 0
(1050 5125);
DISPLAY 0.489362 (1050 5125);
PAINT SKYBLUE (1050 5125);
FORCEPROP 1 LAST PART_NUMBER CH5222KEB01
J 0
(1050 4925);
DISPLAY 0.489362 (1050 4925);
PAINT SKYBLUE (1050 4925);
FORCEPROP 1 LAST VOLTAGE 10V
J 0
(1050 5075);
DISPLAY 0.489362 (1050 5075);
PAINT SKYBLUE (1050 5075);
FORCEPROP 1 LAST PACK_TYPE C0402
J 0
(1050 4875);
DISPLAY 0.489362 (1050 4875);
PAINT SKYBLUE (1050 4875);
FORCEPROP 2 LAST CDS_LIB pure_quanta
J 0
(1000 5075);
DISPLAY INVISIBLE (1000 5075);
FORCEPROP 1 LAST PATH I121
J 0
(1050 5225);
DISPLAY 0.978723 (1050 5225);
PAINT WHITE (1050 5225);
DISPLAY INVISIBLE (1050 5225);
FORCEADD UNIVERSAL_GND..1
(1000 4875);
FORCEPROP 3 LASTPIN (1000 4925) SIG_NAME GND\g
J 0
(1010 4935);
DISPLAY 0.659574 (1010 4935);
PAINT MONO (1010 4935);
DISPLAY INVISIBLE (1010 4935);
FORCEPROP 2 LAST CDS_LIB pure_quanta_power
J 0
(1000 4875);
DISPLAY INVISIBLE (1000 4875);
FORCEPROP 1 LAST PATH I122
J 0
(1075 4875);
DISPLAY 0.872340 (1075 4875);
PAINT AQUA (1075 4875);
DISPLAY INVISIBLE (1075 4875);
FORCEPROP 1 LAST HDL_POWER GND
J 1
(1025 4800);
DISPLAY 0.872340 (1025 4800);
PAINT GREEN (1025 4800);
DISPLAY INVISIBLE (1025 4800);
FORCEADD UNIVERSAL_GND..1
(1350 5375);
FORCEPROP 3 LASTPIN (1350 5425) SIG_NAME GND\g
J 0
(1360 5435);
DISPLAY 0.659574 (1360 5435);
PAINT MONO (1360 5435);
DISPLAY INVISIBLE (1360 5435);
FORCEPROP 2 LAST CDS_LIB pure_quanta_power
J 0
(1350 5375);
DISPLAY INVISIBLE (1350 5375);
FORCEPROP 1 LAST PATH I123
J 0
(1425 5375);
DISPLAY 0.872340 (1425 5375);
PAINT AQUA (1425 5375);
DISPLAY INVISIBLE (1425 5375);
FORCEPROP 1 LAST HDL_POWER GND
J 1
(1375 5300);
DISPLAY 0.872340 (1375 5300);
PAINT GREEN (1375 5300);
DISPLAY INVISIBLE (1375 5300);
FORCEADD Q_RES..2
(1000 5625);
FORCEPROP 1 LAST LOCATION PR277
J 0
(1045 5750);
DISPLAY 0.489362 (1045 5750);
PAINT SKYBLUE (1045 5750);
FORCEPROP 0 LAST $SEC 1
J 0
(1050 5800);
DISPLAY 0.680851 (1050 5800);
PAINT MONO (1050 5800);
DISPLAY INVISIBLE (1050 5800);
FORCEPROP 0 LAST CDS_SEC 1
J 0
(1050 5800);
DISPLAY 1.021277 (1050 5800);
DISPLAY INVISIBLE (1050 5800);
FORCEPROP 1 LASTPIN (1000 5725) $PN 1
J 0
(1005 5687);
DISPLAY 0.489362 (1005 5687);
PAINT MONO (1005 5687);
FORCEPROP 1 LASTPIN (1000 5525) $PN 2
J 0
(1005 5535);
DISPLAY 0.489362 (1005 5535);
PAINT MONO (1005 5535);
FORCEPROP 1 LAST WATTAGE 1/16W
J 0
(1050 5600);
DISPLAY 0.489362 (1050 5600);
PAINT SKYBLUE (1050 5600);
FORCEPROP 1 LAST MATERIAL CHIP
J 0
(1050 5550);
DISPLAY 0.489362 (1050 5550);
PAINT SKYBLUE (1050 5550);
FORCEPROP 1 LAST TOLERANCE 1%
J 0
(1050 5650);
DISPLAY 0.489362 (1050 5650);
PAINT SKYBLUE (1050 5650);
FORCEPROP 1 LAST VALUE 2.2
J 0
(1050 5700);
DISPLAY 0.489362 (1050 5700);
PAINT SKYBLUE (1050 5700);
FORCEPROP 1 LAST PART_NUMBER CS-2202FB00
J 0
(1050 5500);
DISPLAY 0.489362 (1050 5500);
PAINT SKYBLUE (1050 5500);
FORCEPROP 1 LAST PACK_TYPE 0402LF
J 0
(1050 5450);
DISPLAY 0.489362 (1050 5450);
PAINT SKYBLUE (1050 5450);
FORCEPROP 2 LAST CDS_LIB pure_quanta
J 0
(1000 5625);
DISPLAY INVISIBLE (1000 5625);
FORCEPROP 1 LAST PATH I124
J 0
(1050 5800);
DISPLAY 0.978723 (1050 5800);
PAINT WHITE (1050 5800);
DISPLAY INVISIBLE (1050 5800);
FORCEADD Q_CAP..1
(1350 5650);
FORCEPROP 1 LAST LOCATION PC437_IOP1_1
J 0
(1400 5750);
DISPLAY 0.489362 (1400 5750);
PAINT SKYBLUE (1400 5750);
FORCEPROP 0 LAST $SEC 1
J 0
(1400 5800);
DISPLAY 0.680851 (1400 5800);
PAINT MONO (1400 5800);
DISPLAY INVISIBLE (1400 5800);
FORCEPROP 0 LAST CDS_SEC 1
J 0
(1400 5800);
DISPLAY 1.021277 (1400 5800);
DISPLAY INVISIBLE (1400 5800);
FORCEPROP 1 LASTPIN (1350 5750) $PN 1
J 0
(1360 5730);
DISPLAY 0.489362 (1360 5730);
PAINT MONO (1360 5730);
FORCEPROP 1 LASTPIN (1350 5550) $PN 2
J 0
(1360 5530);
DISPLAY 0.489362 (1360 5530);
PAINT MONO (1360 5530);
FORCEPROP 1 LAST MATERIAL X6S
J 0
(1400 5550);
DISPLAY 0.489362 (1400 5550);
PAINT SKYBLUE (1400 5550);
FORCEPROP 1 LAST TOLERANCE 10%
J 0
(1400 5600);
DISPLAY 0.489362 (1400 5600);
PAINT SKYBLUE (1400 5600);
FORCEPROP 1 LAST VALUE 2.2UF
J 0
(1400 5700);
DISPLAY 0.489362 (1400 5700);
PAINT SKYBLUE (1400 5700);
FORCEPROP 1 LAST PART_NUMBER CH5222KEB01
J 0
(1400 5500);
DISPLAY 0.489362 (1400 5500);
PAINT SKYBLUE (1400 5500);
FORCEPROP 1 LAST VOLTAGE 10V
J 0
(1400 5650);
DISPLAY 0.489362 (1400 5650);
PAINT SKYBLUE (1400 5650);
FORCEPROP 1 LAST PACK_TYPE C0402
J 0
(1400 5450);
DISPLAY 0.489362 (1400 5450);
PAINT SKYBLUE (1400 5450);
FORCEPROP 2 LAST CDS_LIB pure_quanta
J 0
(1350 5650);
DISPLAY INVISIBLE (1350 5650);
FORCEPROP 1 LAST PATH I125
J 0
(1400 5800);
DISPLAY 0.978723 (1400 5800);
PAINT WHITE (1400 5800);
DISPLAY INVISIBLE (1400 5800);
FORCEADD Q_CAP..1
(900 2450);
FORCEPROP 1 LAST LOCATION PC432
J 0
(950 2550);
DISPLAY 0.489362 (950 2550);
PAINT SKYBLUE (950 2550);
FORCEPROP 0 LAST $SEC 1
J 0
(950 2600);
DISPLAY 0.680851 (950 2600);
PAINT MONO (950 2600);
DISPLAY INVISIBLE (950 2600);
FORCEPROP 0 LAST CDS_SEC 1
J 0
(950 2600);
DISPLAY 1.021277 (950 2600);
DISPLAY INVISIBLE (950 2600);
FORCEPROP 1 LASTPIN (900 2550) $PN 1
J 0
(910 2530);
DISPLAY 0.489362 (910 2530);
PAINT MONO (910 2530);
FORCEPROP 1 LASTPIN (900 2350) $PN 2
J 0
(910 2330);
DISPLAY 0.489362 (910 2330);
PAINT MONO (910 2330);
FORCEPROP 1 LAST MATERIAL X6S
J 0
(950 2350);
DISPLAY 0.489362 (950 2350);
PAINT SKYBLUE (950 2350);
FORCEPROP 1 LAST PACK_TYPE C0402
J 0
(950 2250);
DISPLAY 0.489362 (950 2250);
PAINT SKYBLUE (950 2250);
FORCEPROP 1 LAST VOLTAGE 10V
J 0
(950 2450);
DISPLAY 0.489362 (950 2450);
PAINT SKYBLUE (950 2450);
FORCEPROP 1 LAST TOLERANCE 10%
J 0
(950 2400);
DISPLAY 0.489362 (950 2400);
PAINT SKYBLUE (950 2400);
FORCEPROP 1 LAST VALUE 2.2UF
J 0
(950 2500);
DISPLAY 0.489362 (950 2500);
PAINT SKYBLUE (950 2500);
FORCEPROP 1 LAST PART_NUMBER CH5222KEB01
J 0
(950 2300);
DISPLAY 0.489362 (950 2300);
PAINT SKYBLUE (950 2300);
FORCEPROP 2 LAST CDS_LIB pure_quanta
J 0
(900 2450);
DISPLAY INVISIBLE (900 2450);
FORCEPROP 1 LAST PATH I127
J 0
(950 2600);
DISPLAY 0.978723 (950 2600);
PAINT WHITE (950 2600);
DISPLAY INVISIBLE (950 2600);
FORCEADD UNIVERSAL_GND..1
(900 2250);
FORCEPROP 3 LASTPIN (900 2300) SIG_NAME GND\g
J 0
(910 2310);
DISPLAY 0.659574 (910 2310);
PAINT MONO (910 2310);
DISPLAY INVISIBLE (910 2310);
FORCEPROP 2 LAST CDS_LIB pure_quanta_power
J 0
(900 2250);
DISPLAY INVISIBLE (900 2250);
FORCEPROP 1 LAST PATH I128
J 0
(975 2250);
DISPLAY 0.872340 (975 2250);
PAINT AQUA (975 2250);
DISPLAY INVISIBLE (975 2250);
FORCEPROP 1 LAST HDL_POWER GND
J 1
(925 2175);
DISPLAY 0.872340 (925 2175);
PAINT GREEN (925 2175);
DISPLAY INVISIBLE (925 2175);
FORCEADD UNIVERSAL_GND..1
(1250 2750);
FORCEPROP 3 LASTPIN (1250 2800) SIG_NAME GND\g
J 0
(1260 2810);
DISPLAY 0.659574 (1260 2810);
PAINT MONO (1260 2810);
DISPLAY INVISIBLE (1260 2810);
FORCEPROP 2 LAST CDS_LIB pure_quanta_power
J 0
(1250 2750);
DISPLAY INVISIBLE (1250 2750);
FORCEPROP 1 LAST PATH I129
J 0
(1325 2750);
DISPLAY 0.872340 (1325 2750);
PAINT AQUA (1325 2750);
DISPLAY INVISIBLE (1325 2750);
FORCEPROP 1 LAST HDL_POWER GND
J 1
(1275 2675);
DISPLAY 0.872340 (1275 2675);
PAINT GREEN (1275 2675);
DISPLAY INVISIBLE (1275 2675);
FORCEADD UNIVERSAL_GND..1
(575 4125);
FORCEPROP 3 LASTPIN (575 4175) SIG_NAME GND\g
J 0
(585 4185);
DISPLAY 0.659574 (585 4185);
PAINT MONO (585 4185);
DISPLAY INVISIBLE (585 4185);
FORCEPROP 2 LAST CDS_LIB pure_quanta_power
J 0
(575 4125);
PAINT MONO (575 4125);
DISPLAY INVISIBLE (575 4125);
FORCEPROP 1 LAST PATH I13
J 0
(650 4125);
DISPLAY 0.872340 (650 4125);
PAINT AQUA (650 4125);
DISPLAY INVISIBLE (650 4125);
FORCEPROP 1 LAST HDL_POWER GND
J 1
(600 4050);
DISPLAY 0.872340 (600 4050);
PAINT GREEN (600 4050);
DISPLAY INVISIBLE (600 4050);
FORCEADD Q_RES..2
(900 3000);
FORCEPROP 1 LAST LOCATION PR276
J 0
(945 3125);
DISPLAY 0.489362 (945 3125);
PAINT SKYBLUE (945 3125);
FORCEPROP 0 LAST $SEC 1
J 0
(950 3175);
DISPLAY 0.680851 (950 3175);
PAINT MONO (950 3175);
DISPLAY INVISIBLE (950 3175);
FORCEPROP 0 LAST CDS_SEC 1
J 0
(950 3175);
DISPLAY 1.021277 (950 3175);
DISPLAY INVISIBLE (950 3175);
FORCEPROP 1 LASTPIN (900 3100) $PN 1
J 0
(905 3062);
DISPLAY 0.489362 (905 3062);
PAINT MONO (905 3062);
FORCEPROP 1 LASTPIN (900 2900) $PN 2
J 0
(905 2910);
DISPLAY 0.489362 (905 2910);
PAINT MONO (905 2910);
FORCEPROP 1 LAST WATTAGE 1/16W
J 0
(950 2975);
DISPLAY 0.489362 (950 2975);
PAINT SKYBLUE (950 2975);
FORCEPROP 1 LAST MATERIAL CHIP
J 0
(950 2925);
DISPLAY 0.489362 (950 2925);
PAINT SKYBLUE (950 2925);
FORCEPROP 1 LAST TOLERANCE 1%
J 0
(950 3025);
DISPLAY 0.489362 (950 3025);
PAINT SKYBLUE (950 3025);
FORCEPROP 1 LAST VALUE 2.2
J 0
(950 3075);
DISPLAY 0.489362 (950 3075);
PAINT SKYBLUE (950 3075);
FORCEPROP 1 LAST PART_NUMBER CS-2202FB00
J 0
(950 2875);
DISPLAY 0.489362 (950 2875);
PAINT SKYBLUE (950 2875);
FORCEPROP 1 LAST PACK_TYPE 0402LF
J 0
(950 2825);
DISPLAY 0.489362 (950 2825);
PAINT SKYBLUE (950 2825);
FORCEPROP 2 LAST CDS_LIB pure_quanta
J 0
(900 3000);
DISPLAY INVISIBLE (900 3000);
FORCEPROP 1 LAST PATH I130
J 0
(950 3175);
DISPLAY 0.978723 (950 3175);
PAINT WHITE (950 3175);
DISPLAY INVISIBLE (950 3175);
FORCEADD Q_CAP..1
(1250 3025);
FORCEPROP 1 LAST LOCATION PC434_IOP1_2
J 0
(1300 3125);
DISPLAY 0.489362 (1300 3125);
PAINT SKYBLUE (1300 3125);
FORCEPROP 0 LAST $SEC 1
J 0
(1300 3175);
DISPLAY 0.680851 (1300 3175);
PAINT MONO (1300 3175);
DISPLAY INVISIBLE (1300 3175);
FORCEPROP 0 LAST CDS_SEC 1
J 0
(1300 3175);
DISPLAY 1.021277 (1300 3175);
DISPLAY INVISIBLE (1300 3175);
FORCEPROP 1 LASTPIN (1250 3125) $PN 1
J 0
(1260 3105);
DISPLAY 0.489362 (1260 3105);
PAINT MONO (1260 3105);
FORCEPROP 1 LASTPIN (1250 2925) $PN 2
J 0
(1260 2905);
DISPLAY 0.489362 (1260 2905);
PAINT MONO (1260 2905);
FORCEPROP 1 LAST MATERIAL X6S
J 0
(1300 2925);
DISPLAY 0.489362 (1300 2925);
PAINT SKYBLUE (1300 2925);
FORCEPROP 1 LAST TOLERANCE 10%
J 0
(1300 2975);
DISPLAY 0.489362 (1300 2975);
PAINT SKYBLUE (1300 2975);
FORCEPROP 1 LAST VALUE 2.2UF
J 0
(1300 3075);
DISPLAY 0.489362 (1300 3075);
PAINT SKYBLUE (1300 3075);
FORCEPROP 1 LAST PART_NUMBER CH5222KEB01
J 0
(1300 2875);
DISPLAY 0.489362 (1300 2875);
PAINT SKYBLUE (1300 2875);
FORCEPROP 1 LAST VOLTAGE 10V
J 0
(1300 3025);
DISPLAY 0.489362 (1300 3025);
PAINT SKYBLUE (1300 3025);
FORCEPROP 1 LAST PACK_TYPE C0402
J 0
(1300 2825);
DISPLAY 0.489362 (1300 2825);
PAINT SKYBLUE (1300 2825);
FORCEPROP 2 LAST CDS_LIB pure_quanta
J 0
(1250 3025);
DISPLAY INVISIBLE (1250 3025);
FORCEPROP 1 LAST PATH I131
J 0
(1300 3175);
DISPLAY 0.978723 (1300 3175);
PAINT WHITE (1300 3175);
DISPLAY INVISIBLE (1300 3175);
FORCEADD UNIVERSAL_GND..1
(25 4225);
FORCEPROP 3 LASTPIN (25 4275) SIG_NAME GND\g
J 0
(35 4285);
DISPLAY 0.659574 (35 4285);
PAINT MONO (35 4285);
DISPLAY INVISIBLE (35 4285);
FORCEPROP 2 LAST CDS_LIB pure_quanta_power
J 0
(25 4225);
DISPLAY INVISIBLE (25 4225);
FORCEPROP 1 LAST PATH I133
J 0
(100 4225);
DISPLAY 0.872340 (100 4225);
PAINT AQUA (100 4225);
DISPLAY INVISIBLE (100 4225);
FORCEPROP 1 LAST HDL_POWER GND
J 1
(50 4150);
DISPLAY 0.872340 (50 4150);
PAINT GREEN (50 4150);
DISPLAY INVISIBLE (50 4150);
FORCEADD UNIVERSAL_GND..1
(25 1475);
FORCEPROP 3 LASTPIN (25 1525) SIG_NAME GND\g
J 0
(35 1535);
DISPLAY 0.659574 (35 1535);
PAINT MONO (35 1535);
DISPLAY INVISIBLE (35 1535);
FORCEPROP 2 LAST CDS_LIB pure_quanta_power
J 0
(25 1475);
DISPLAY INVISIBLE (25 1475);
FORCEPROP 1 LAST PATH I134
J 0
(100 1475);
DISPLAY 0.872340 (100 1475);
PAINT AQUA (100 1475);
DISPLAY INVISIBLE (100 1475);
FORCEPROP 1 LAST HDL_POWER GND
J 1
(50 1400);
DISPLAY 0.872340 (50 1400);
PAINT GREEN (50 1400);
DISPLAY INVISIBLE (50 1400);
FORCEADD OFFPAGE..3
(6825 1800);
FORCEPROP 2 LAST $XR0 198 
J 0
(7069 1800);
DISPLAY 0.638298 (7069 1800);
PAINT MONO (7069 1800);
FORCEPROP 2 LAST CDS_LIB standard
J 0
(6825 1800);
DISPLAY INVISIBLE (6825 1800);
FORCEPROP 1 LAST OFFPAGE TRUE
J 0
(7150 1675);
DISPLAY 0.872340 (7150 1675);
PAINT GREEN (7150 1675);
DISPLAY INVISIBLE (7150 1675);
FORCEPROP 1 LAST COMMENT_BODY TRUE
J 0
(6775 1700);
DISPLAY 0.872340 (6775 1700);
PAINT GREEN (6775 1700);
DISPLAY INVISIBLE (6775 1700);
FORCEPROP 2 LAST PATH I135
J 0
(7025 1875);
DISPLAY 1.021277 (7025 1875);
DISPLAY INVISIBLE (7025 1875);
FORCEADD UNIVERSAL_GND..1
(4050 3875);
FORCEPROP 3 LASTPIN (4050 3925) SIG_NAME GND\g
J 0
(4060 3935);
DISPLAY 0.659574 (4060 3935);
PAINT MONO (4060 3935);
DISPLAY INVISIBLE (4060 3935);
FORCEPROP 2 LAST CDS_LIB pure_quanta_power
J 0
(4050 3875);
DISPLAY INVISIBLE (4050 3875);
FORCEPROP 1 LAST PATH I136
J 0
(4125 3875);
DISPLAY 0.872340 (4125 3875);
PAINT AQUA (4125 3875);
DISPLAY INVISIBLE (4125 3875);
FORCEPROP 1 LAST HDL_POWER GND
J 1
(4075 3800);
DISPLAY 0.872340 (4075 3800);
PAINT GREEN (4075 3800);
DISPLAY INVISIBLE (4075 3800);
FORCEADD Q_RES..2
(4050 4100);
FORCEPROP 1 LAST LOCATION PR488
J 0
(4095 4225);
DISPLAY 0.489362 (4095 4225);
PAINT SKYBLUE (4095 4225);
FORCEPROP 0 LAST $SEC 1
J 0
(4100 4275);
DISPLAY 0.680851 (4100 4275);
PAINT MONO (4100 4275);
DISPLAY INVISIBLE (4100 4275);
FORCEPROP 0 LAST CDS_SEC 1
J 0
(4100 4275);
DISPLAY 1.021277 (4100 4275);
DISPLAY INVISIBLE (4100 4275);
FORCEPROP 1 LASTPIN (4050 4200) $PN 1
J 0
(4055 4162);
DISPLAY 0.489362 (4055 4162);
PAINT MONO (4055 4162);
FORCEPROP 1 LASTPIN (4050 4000) $PN 2
J 0
(4055 4010);
DISPLAY 0.489362 (4055 4010);
PAINT MONO (4055 4010);
FORCEPROP 1 LAST WATTAGE 1/8W
J 0
(4090 4075);
DISPLAY 0.489362 (4090 4075);
PAINT SKYBLUE (4090 4075);
FORCEPROP 1 LAST MATERIAL EMPTY
J 0
(4090 4025);
DISPLAY 0.489362 (4090 4025);
PAINT RED (4090 4025);
FORCEPROP 1 LAST TOLERANCE 1%
J 0
(4095 4125);
DISPLAY 0.489362 (4095 4125);
PAINT SKYBLUE (4095 4125);
FORCEPROP 1 LAST VALUE 1.5
J 0
(4095 4175);
DISPLAY 0.489362 (4095 4175);
PAINT SKYBLUE (4095 4175);
FORCEPROP 1 LAST PART_NUMBER CS-1504FB00
J 0
(4090 3975);
DISPLAY 0.489362 (4090 3975);
PAINT SKYBLUE (4090 3975);
FORCEPROP 1 LAST PACK_TYPE 0402LF
J 0
(4090 3925);
DISPLAY 0.489362 (4090 3925);
PAINT SKYBLUE (4090 3925);
FORCEPROP 2 LAST CDS_LIB pure_quanta
J 0
(4050 4100);
DISPLAY INVISIBLE (4050 4100);
FORCEPROP 1 LAST PATH I137
J 0
(4100 4275);
DISPLAY 0.978723 (4100 4275);
PAINT WHITE (4100 4275);
DISPLAY INVISIBLE (4100 4275);
FORCEADD Q_CAP..1
(4050 4600);
FORCEPROP 1 LAST LOCATION PC174
J 0
(4100 4700);
DISPLAY 0.489362 (4100 4700);
PAINT SKYBLUE (4100 4700);
FORCEPROP 0 LAST $SEC 1
J 0
(4100 4750);
DISPLAY 0.680851 (4100 4750);
PAINT MONO (4100 4750);
DISPLAY INVISIBLE (4100 4750);
FORCEPROP 0 LAST CDS_SEC 1
J 0
(4100 4750);
DISPLAY 1.021277 (4100 4750);
DISPLAY INVISIBLE (4100 4750);
FORCEPROP 1 LASTPIN (4050 4700) $PN 1
J 0
(4060 4680);
DISPLAY 0.489362 (4060 4680);
PAINT MONO (4060 4680);
FORCEPROP 1 LASTPIN (4050 4500) $PN 2
J 0
(4060 4480);
DISPLAY 0.489362 (4060 4480);
PAINT MONO (4060 4480);
FORCEPROP 1 LAST MATERIAL EMPTY
J 0
(4100 4500);
DISPLAY 0.489362 (4100 4500);
PAINT RED (4100 4500);
FORCEPROP 1 LAST TOLERANCE 10%
J 0
(4100 4550);
DISPLAY 0.489362 (4100 4550);
PAINT SKYBLUE (4100 4550);
FORCEPROP 1 LAST VALUE 560PF
J 0
(4100 4650);
DISPLAY 0.489362 (4100 4650);
PAINT SKYBLUE (4100 4650);
FORCEPROP 1 LAST PART_NUMBER CH1566K1B09
J 0
(4100 4450);
DISPLAY 0.489362 (4100 4450);
PAINT SKYBLUE (4100 4450);
FORCEPROP 1 LAST VOLTAGE 50V
J 0
(4100 4600);
DISPLAY 0.489362 (4100 4600);
PAINT SKYBLUE (4100 4600);
FORCEPROP 1 LAST PACK_TYPE C0402
J 0
(4100 4400);
DISPLAY 0.489362 (4100 4400);
PAINT SKYBLUE (4100 4400);
FORCEPROP 2 LAST CDS_LIB pure_quanta
J 0
(4050 4600);
DISPLAY INVISIBLE (4050 4600);
FORCEPROP 1 LAST PATH I138
J 0
(4100 4750);
DISPLAY 0.978723 (4100 4750);
PAINT WHITE (4100 4750);
DISPLAY INVISIBLE (4100 4750);
FORCEADD Q_CAP..1
(3950 1850);
FORCEPROP 1 LAST LOCATION PC175
J 0
(4000 1950);
DISPLAY 0.489362 (4000 1950);
PAINT SKYBLUE (4000 1950);
FORCEPROP 0 LAST $SEC 1
J 0
(4000 2000);
DISPLAY 0.680851 (4000 2000);
PAINT MONO (4000 2000);
DISPLAY INVISIBLE (4000 2000);
FORCEPROP 0 LAST CDS_SEC 1
J 0
(4000 2000);
DISPLAY 1.021277 (4000 2000);
DISPLAY INVISIBLE (4000 2000);
FORCEPROP 1 LASTPIN (3950 1950) $PN 1
J 0
(3960 1930);
DISPLAY 0.489362 (3960 1930);
PAINT MONO (3960 1930);
FORCEPROP 1 LASTPIN (3950 1750) $PN 2
J 0
(3960 1730);
DISPLAY 0.489362 (3960 1730);
PAINT MONO (3960 1730);
FORCEPROP 1 LAST PART_NUMBER CH1566K1B09
J 0
(4000 1700);
DISPLAY 0.489362 (4000 1700);
PAINT SKYBLUE (4000 1700);
FORCEPROP 1 LAST PACK_TYPE C0402
J 0
(4000 1650);
DISPLAY 0.489362 (4000 1650);
PAINT SKYBLUE (4000 1650);
FORCEPROP 1 LAST MATERIAL EMPTY
J 0
(4000 1750);
DISPLAY 0.489362 (4000 1750);
PAINT RED (4000 1750);
FORCEPROP 1 LAST TOLERANCE 10%
J 0
(4000 1800);
DISPLAY 0.489362 (4000 1800);
PAINT SKYBLUE (4000 1800);
FORCEPROP 1 LAST VALUE 560PF
J 0
(4000 1900);
DISPLAY 0.489362 (4000 1900);
PAINT SKYBLUE (4000 1900);
FORCEPROP 1 LAST VOLTAGE 50V
J 0
(4000 1850);
DISPLAY 0.489362 (4000 1850);
PAINT SKYBLUE (4000 1850);
FORCEPROP 2 LAST CDS_LIB pure_quanta
J 0
(3950 1850);
DISPLAY INVISIBLE (3950 1850);
FORCEPROP 1 LAST PATH I139
J 0
(4000 2000);
DISPLAY 0.978723 (4000 2000);
PAINT WHITE (4000 2000);
DISPLAY INVISIBLE (4000 2000);
FORCEADD Q_RES..2
(3950 1350);
FORCEPROP 1 LAST LOCATION PR489
J 0
(3995 1475);
DISPLAY 0.489362 (3995 1475);
PAINT SKYBLUE (3995 1475);
FORCEPROP 0 LAST $SEC 1
J 0
(4000 1525);
DISPLAY 0.680851 (4000 1525);
PAINT MONO (4000 1525);
DISPLAY INVISIBLE (4000 1525);
FORCEPROP 0 LAST CDS_SEC 1
J 0
(4000 1525);
DISPLAY 1.021277 (4000 1525);
DISPLAY INVISIBLE (4000 1525);
FORCEPROP 1 LASTPIN (3950 1450) $PN 1
J 0
(3955 1412);
DISPLAY 0.489362 (3955 1412);
PAINT MONO (3955 1412);
FORCEPROP 1 LASTPIN (3950 1250) $PN 2
J 0
(3955 1260);
DISPLAY 0.489362 (3955 1260);
PAINT MONO (3955 1260);
FORCEPROP 1 LAST TOLERANCE 1%
J 0
(3995 1375);
DISPLAY 0.489362 (3995 1375);
PAINT SKYBLUE (3995 1375);
FORCEPROP 1 LAST VALUE 1.5
J 0
(3995 1425);
DISPLAY 0.489362 (3995 1425);
PAINT SKYBLUE (3995 1425);
FORCEPROP 1 LAST WATTAGE 1/8W
J 0
(3990 1325);
DISPLAY 0.489362 (3990 1325);
PAINT SKYBLUE (3990 1325);
FORCEPROP 1 LAST MATERIAL EMPTY
J 0
(3990 1275);
DISPLAY 0.489362 (3990 1275);
PAINT RED (3990 1275);
FORCEPROP 1 LAST PART_NUMBER CS-1504FB00
J 0
(3990 1225);
DISPLAY 0.489362 (3990 1225);
PAINT SKYBLUE (3990 1225);
FORCEPROP 1 LAST PACK_TYPE 0402LF
J 0
(3990 1175);
DISPLAY 0.489362 (3990 1175);
PAINT SKYBLUE (3990 1175);
FORCEPROP 2 LAST CDS_LIB pure_quanta
J 0
(3950 1350);
DISPLAY INVISIBLE (3950 1350);
FORCEPROP 1 LAST PATH I140
J 0
(4000 1525);
DISPLAY 0.978723 (4000 1525);
PAINT WHITE (4000 1525);
DISPLAY INVISIBLE (4000 1525);
FORCEADD UNIVERSAL_GND..1
(3950 1125);
FORCEPROP 3 LASTPIN (3950 1175) SIG_NAME GND\g
J 0
(3960 1185);
DISPLAY 0.659574 (3960 1185);
PAINT MONO (3960 1185);
DISPLAY INVISIBLE (3960 1185);
FORCEPROP 2 LAST CDS_LIB pure_quanta_power
J 0
(3950 1125);
DISPLAY INVISIBLE (3950 1125);
FORCEPROP 1 LAST PATH I141
J 0
(4025 1125);
DISPLAY 0.872340 (4025 1125);
PAINT AQUA (4025 1125);
DISPLAY INVISIBLE (4025 1125);
FORCEPROP 1 LAST HDL_POWER GND
J 1
(3975 1050);
DISPLAY 0.872340 (3975 1050);
PAINT GREEN (3975 1050);
DISPLAY INVISIBLE (3975 1050);
FORCEADD VCC_CORE..1
(1000 6025);
FORCEPROP 3 LASTPIN (1000 5975) SIG_NAME PVDDCR_CPU1_P1_PVCC\g
J 0
(1010 5985);
DISPLAY 0.659574 (1010 5985);
PAINT MONO (1010 5985);
DISPLAY INVISIBLE (1010 5985);
FORCEPROP 1 LAST HDL_POWER PVDDCR_CPU1_P1_PVCC
J 1
(1000 6075);
DISPLAY 0.489362 (1000 6075);
PAINT GREEN (1000 6075);
FORCEPROP 2 LAST CDS_LIB pure_quanta_power
J 0
(1000 6025);
DISPLAY INVISIBLE (1000 6025);
FORCEPROP 1 LAST PATH I142
J 0
(1050 6050);
DISPLAY 0.872340 (1050 6050);
PAINT AQUA (1050 6050);
DISPLAY INVISIBLE (1050 6050);
FORCEADD VCC_CORE..1
(900 3400);
FORCEPROP 3 LASTPIN (900 3350) SIG_NAME PVDDCR_CPU1_P1_PVCC\g
J 0
(910 3360);
DISPLAY 0.659574 (910 3360);
PAINT MONO (910 3360);
DISPLAY INVISIBLE (910 3360);
FORCEPROP 1 LAST HDL_POWER PVDDCR_CPU1_P1_PVCC
J 1
(900 3450);
DISPLAY 0.489362 (900 3450);
PAINT GREEN (900 3450);
FORCEPROP 2 LAST CDS_LIB pure_quanta_power
J 0
(900 3400);
DISPLAY INVISIBLE (900 3400);
FORCEPROP 1 LAST PATH I143
J 0
(950 3425);
DISPLAY 0.872340 (950 3425);
PAINT AQUA (950 3425);
DISPLAY INVISIBLE (950 3425);
FORCEADD Q_RES..2
(8175 4600);
FORCEPROP 1 LAST LOCATION PR378
J 0
(8220 4725);
DISPLAY 0.489362 (8220 4725);
PAINT SKYBLUE (8220 4725);
FORCEPROP 0 LAST $SEC 1
J 0
(8225 4750);
DISPLAY 0.680851 (8225 4750);
PAINT MONO (8225 4750);
DISPLAY INVISIBLE (8225 4750);
FORCEPROP 0 LAST CDS_SEC 1
J 0
(8225 4750);
DISPLAY 1.021277 (8225 4750);
DISPLAY INVISIBLE (8225 4750);
FORCEPROP 1 LASTPIN (8175 4700) $PN 1
J 0
(8180 4662);
DISPLAY 0.787234 (8180 4662);
PAINT MONO (8180 4662);
DISPLAY INVISIBLE (8180 4662);
FORCEPROP 1 LASTPIN (8175 4500) $PN 2
J 0
(8180 4510);
DISPLAY 0.787234 (8180 4510);
PAINT MONO (8180 4510);
DISPLAY INVISIBLE (8180 4510);
FORCEPROP 1 LAST WATTAGE 1/16W
J 0
(8215 4575);
DISPLAY 0.489362 (8215 4575);
PAINT SKYBLUE (8215 4575);
FORCEPROP 1 LAST MATERIAL CHIP
J 0
(8215 4525);
DISPLAY 0.489362 (8215 4525);
PAINT SKYBLUE (8215 4525);
FORCEPROP 1 LAST TOLERANCE 1%
J 0
(8220 4625);
DISPLAY 0.489362 (8220 4625);
PAINT SKYBLUE (8220 4625);
FORCEPROP 1 LAST VALUE 1K
J 0
(8220 4675);
DISPLAY 0.489362 (8220 4675);
PAINT SKYBLUE (8220 4675);
FORCEPROP 1 LAST PART_NUMBER TMP_QCS21002FB24
J 0
(8215 4475);
DISPLAY 0.489362 (8215 4475);
PAINT SKYBLUE (8215 4475);
FORCEPROP 1 LAST PACK_TYPE 0402LF
J 0
(8215 4425);
DISPLAY 0.489362 (8215 4425);
PAINT SKYBLUE (8215 4425);
FORCEPROP 2 LAST CDS_LIB pure_quanta
J 0
(8175 4600);
DISPLAY INVISIBLE (8175 4600);
FORCEPROP 1 LAST PATH I144
J 0
(8225 4775);
DISPLAY 0.978723 (8225 4775);
PAINT WHITE (8225 4775);
DISPLAY INVISIBLE (8225 4775);
FORCEADD OFFPAGE..6
(4775 4550);
FORCEPROP 2 LAST $XR0 198 
J 0
(4465 4550);
DISPLAY 0.638298 (4465 4550);
PAINT MONO (4465 4550);
FORCEPROP 2 LAST PATH I145
J 0
(4500 4600);
DISPLAY 1.021277 (4500 4600);
DISPLAY INVISIBLE (4500 4600);
FORCEPROP 2 LAST CDS_LIB standard
J 0
(4775 4550);
DISPLAY INVISIBLE (4775 4550);
FORCEPROP 1 LAST OFFPAGE TRUE
J 0
(5100 4425);
DISPLAY 0.872340 (5100 4425);
PAINT GREEN (5100 4425);
DISPLAY INVISIBLE (5100 4425);
FORCEPROP 1 LAST COMMENT_BODY TRUE
J 0
(4875 4475);
DISPLAY 0.872340 (4875 4475);
PAINT GREEN (4875 4475);
DISPLAY INVISIBLE (4875 4475);
FORCEADD UNIVERSAL_GND..1
(6700 4425);
FORCEPROP 3 LASTPIN (6700 4475) SIG_NAME GND\g
J 0
(6710 4485);
DISPLAY 0.659574 (6710 4485);
PAINT MONO (6710 4485);
DISPLAY INVISIBLE (6710 4485);
FORCEPROP 2 LAST CDS_LIB pure_quanta_power
J 0
(6700 4425);
DISPLAY INVISIBLE (6700 4425);
FORCEPROP 1 LAST PATH I146
J 0
(6775 4425);
DISPLAY 0.872340 (6775 4425);
PAINT AQUA (6775 4425);
DISPLAY INVISIBLE (6775 4425);
FORCEPROP 1 LAST HDL_POWER GND
J 1
(6725 4350);
DISPLAY 0.872340 (6725 4350);
PAINT GREEN (6725 4350);
DISPLAY INVISIBLE (6725 4350);
FORCEADD OFFPAGE..1
(1050 4200);
FORCEPROP 2 LAST $XR0 193 
J 0
(798 4200);
DISPLAY 0.638298 (798 4200);
PAINT MONO (798 4200);
FORCEPROP 2 LAST PATH I16
J 0
(625 4250);
DISPLAY 1.021277 (625 4250);
DISPLAY INVISIBLE (625 4250);
FORCEPROP 1 LAST COMMENT_BODY TRUE
J 0
(1175 4100);
DISPLAY 0.872340 (1175 4100);
PAINT GREEN (1175 4100);
DISPLAY INVISIBLE (1175 4100);
FORCEPROP 1 LAST OFFPAGE TRUE
J 0
(1375 4075);
DISPLAY 0.872340 (1375 4075);
PAINT GREEN (1375 4075);
DISPLAY INVISIBLE (1375 4075);
FORCEPROP 2 LAST CDS_LIB standard
J 0
(1050 4200);
DISPLAY INVISIBLE (1050 4200);
FORCEADD Q_RES..2
R 2
(575 4350);
FORCEPROP 1 LAST LOCATION PR275
J 2
(530 4475);
DISPLAY 0.489362 (530 4475);
PAINT SKYBLUE (530 4475);
FORCEPROP 0 LAST $SEC 1
J 2
(525 4525);
DISPLAY 0.680851 (525 4525);
PAINT MONO (525 4525);
DISPLAY INVISIBLE (525 4525);
FORCEPROP 0 LAST CDS_SEC 1
J 2
(525 4525);
DISPLAY 1.021277 (525 4525);
DISPLAY INVISIBLE (525 4525);
FORCEPROP 1 LASTPIN (575 4450) $PN 1
J 2
(570 4412);
DISPLAY 0.489362 (570 4412);
PAINT MONO (570 4412);
FORCEPROP 1 LASTPIN (575 4250) $PN 2
J 2
(570 4260);
DISPLAY 0.489362 (570 4260);
PAINT MONO (570 4260);
FORCEPROP 1 LAST PACK_TYPE 0402LF
J 2
(525 4175);
DISPLAY 0.489362 (525 4175);
PAINT SKYBLUE (525 4175);
FORCEPROP 1 LAST WATTAGE 1/16W
J 2
(525 4325);
DISPLAY 0.489362 (525 4325);
PAINT SKYBLUE (525 4325);
FORCEPROP 1 LAST MATERIAL EMPTY
J 2
(525 4275);
DISPLAY 0.489362 (525 4275);
PAINT RED (525 4275);
FORCEPROP 1 LAST TOLERANCE 1%
J 2
(520 4375);
DISPLAY 0.489362 (520 4375);
PAINT SKYBLUE (520 4375);
FORCEPROP 1 LAST VALUE 8.87K
J 2
(520 4425);
DISPLAY 0.489362 (520 4425);
PAINT SKYBLUE (520 4425);
FORCEPROP 1 LAST PART_NUMBER CS28872FB01
J 2
(525 4225);
DISPLAY 0.489362 (525 4225);
PAINT SKYBLUE (525 4225);
FORCEPROP 2 LAST CDS_LIB pure_quanta
J 2
(575 4350);
DISPLAY INVISIBLE (575 4350);
FORCEPROP 1 LAST PATH I17
J 2
(525 4525);
DISPLAY 0.978723 (525 4525);
PAINT WHITE (525 4525);
DISPLAY INVISIBLE (525 4525);
FORCEADD Q_RES..2
R 2
(550 1550);
FORCEPROP 1 LAST LOCATION PR274
J 2
(505 1675);
DISPLAY 0.489362 (505 1675);
PAINT SKYBLUE (505 1675);
FORCEPROP 0 LAST $SEC 1
J 2
(500 1725);
DISPLAY 0.680851 (500 1725);
PAINT MONO (500 1725);
DISPLAY INVISIBLE (500 1725);
FORCEPROP 0 LAST CDS_SEC 1
J 2
(500 1725);
DISPLAY 1.021277 (500 1725);
DISPLAY INVISIBLE (500 1725);
FORCEPROP 1 LASTPIN (550 1650) $PN 1
J 2
(545 1612);
DISPLAY 0.489362 (545 1612);
PAINT MONO (545 1612);
FORCEPROP 1 LASTPIN (550 1450) $PN 2
J 2
(545 1460);
DISPLAY 0.489362 (545 1460);
PAINT MONO (545 1460);
FORCEPROP 1 LAST WATTAGE 1/16W
J 2
(500 1525);
DISPLAY 0.489362 (500 1525);
PAINT SKYBLUE (500 1525);
FORCEPROP 1 LAST MATERIAL EMPTY
J 2
(500 1475);
DISPLAY 0.489362 (500 1475);
PAINT RED (500 1475);
FORCEPROP 1 LAST TOLERANCE 1%
J 2
(495 1575);
DISPLAY 0.489362 (495 1575);
PAINT SKYBLUE (495 1575);
FORCEPROP 1 LAST VALUE 8.87K
J 2
(495 1625);
DISPLAY 0.489362 (495 1625);
PAINT SKYBLUE (495 1625);
FORCEPROP 1 LAST PART_NUMBER CS28872FB01
J 2
(500 1425);
DISPLAY 0.489362 (500 1425);
PAINT SKYBLUE (500 1425);
FORCEPROP 1 LAST PACK_TYPE 0402LF
J 2
(500 1375);
DISPLAY 0.489362 (500 1375);
PAINT SKYBLUE (500 1375);
FORCEPROP 2 LAST CDS_LIB pure_quanta
J 2
(550 1550);
DISPLAY INVISIBLE (550 1550);
FORCEPROP 1 LAST PATH I2
J 2
(500 1725);
DISPLAY 0.978723 (500 1725);
PAINT WHITE (500 1725);
DISPLAY INVISIBLE (500 1725);
FORCEADD OFFPAGE..1
(1050 4700);
FORCEPROP 2 LAST $XR5 199 
J 0
(198 4700);
DISPLAY 0.638298 (198 4700);
PAINT MONO (198 4700);
FORCEPROP 2 LAST $XR4 198 
J 0
(318 4700);
DISPLAY 0.638298 (318 4700);
PAINT MONO (318 4700);
FORCEPROP 2 LAST $XR3 196 
J 0
(438 4700);
DISPLAY 0.638298 (438 4700);
PAINT MONO (438 4700);
FORCEPROP 2 LAST $XR2 195 
J 0
(558 4700);
DISPLAY 0.638298 (558 4700);
PAINT MONO (558 4700);
FORCEPROP 2 LAST $XR1 194 
J 0
(678 4700);
DISPLAY 0.638298 (678 4700);
PAINT MONO (678 4700);
FORCEPROP 2 LAST $XR0 193 
J 0
(798 4700);
DISPLAY 0.638298 (798 4700);
PAINT MONO (798 4700);
FORCEPROP 2 LAST PATH I20
J 0
(800 4750);
DISPLAY 1.021277 (800 4750);
DISPLAY INVISIBLE (800 4750);
FORCEPROP 1 LAST COMMENT_BODY TRUE
J 0
(1175 4600);
DISPLAY 0.872340 (1175 4600);
PAINT GREEN (1175 4600);
DISPLAY INVISIBLE (1175 4600);
FORCEPROP 1 LAST OFFPAGE TRUE
J 0
(1375 4575);
DISPLAY 0.872340 (1375 4575);
PAINT GREEN (1375 4575);
DISPLAY INVISIBLE (1375 4575);
FORCEPROP 2 LAST CDS_LIB standard
J 0
(1050 4700);
DISPLAY INVISIBLE (1050 4700);
FORCEADD OFFPAGE..5
(1050 4800);
FORCEPROP 2 LAST $XR0 193 
J 0
(765 4800);
DISPLAY 0.638298 (765 4800);
PAINT MONO (765 4800);
FORCEPROP 2 LAST PATH I21
J 0
(800 4850);
DISPLAY 1.021277 (800 4850);
DISPLAY INVISIBLE (800 4850);
FORCEPROP 1 LAST COMMENT_BODY TRUE
J 0
(1150 4725);
DISPLAY 0.872340 (1150 4725);
PAINT GREEN (1150 4725);
DISPLAY INVISIBLE (1150 4725);
FORCEPROP 1 LAST OFFPAGE TRUE
J 0
(1375 4675);
DISPLAY 0.872340 (1375 4675);
PAINT GREEN (1375 4675);
DISPLAY INVISIBLE (1375 4675);
FORCEPROP 2 LAST CDS_LIB standard
J 0
(1050 4800);
DISPLAY INVISIBLE (1050 4800);
FORCEADD ISL99390FRZTR5935..1
(2575 2050);
FORCEPROP 1 LAST LOCATION PU40
J 0
(2275 2925);
DISPLAY 0.489362 (2275 2925);
PAINT SKYBLUE (2275 2925);
FORCEPROP 2 LAST $SEC 1
J 0
(2275 2975);
DISPLAY 0.680851 (2275 2975);
PAINT MONO (2275 2975);
DISPLAY INVISIBLE (2275 2975);
FORCEPROP 2 LAST CDS_SEC 1
J 0
(2325 3050);
DISPLAY 1.021277 (2325 3050);
DISPLAY INVISIBLE (2325 3050);
FORCEPROP 2 LASTPIN (2975 1600) $PN 2
J 0
(2985 1610);
DISPLAY 0.489362 (2985 1610);
PAINT MONO (2985 1610);
FORCEPROP 2 LASTPIN (2975 2400) $PN 33
J 0
(2985 2410);
DISPLAY 0.489362 (2985 2410);
PAINT MONO (2985 2410);
FORCEPROP 2 LASTPIN (2125 1800) $PN 31
J 2
(2115 1810);
DISPLAY 0.489362 (2115 1810);
PAINT MONO (2115 1810);
FORCEPROP 2 LASTPIN (2125 2200) $PN 35
J 2
(2115 2210);
DISPLAY 0.489362 (2115 2210);
PAINT MONO (2115 2210);
FORCEPROP 2 LASTPIN (2975 1750) $PN 6
J 0
(2985 1760);
DISPLAY 0.489362 (2985 1760);
PAINT MONO (2985 1760);
FORCEPROP 2 LASTPIN (2975 1700) $PN 41
J 0
(2985 1710);
DISPLAY 0.489362 (2985 1710);
PAINT MONO (2985 1710);
FORCEPROP 2 LASTPIN (2125 2050) $PN 38
J 2
(2115 2060);
DISPLAY 0.489362 (2115 2060);
PAINT MONO (2115 2060);
FORCEPROP 2 LASTPIN (2125 1750) $PN 37
J 2
(2115 1760);
DISPLAY 0.489362 (2115 1760);
PAINT MONO (2115 1760);
FORCEPROP 2 LASTPIN (2975 1550) $PN 5
J 0
(2985 1560);
DISPLAY 0.489362 (2985 1560);
PAINT MONO (2985 1560);
FORCEPROP 2 LASTPIN (2975 1500) $PN 7_9-20_24
J 0
(2985 1510);
DISPLAY 0.489362 (2985 1510);
PAINT MONO (2985 1510);
FORCEPROP 2 LASTPIN (2975 1450) $PN 40
J 0
(2985 1460);
DISPLAY 0.489362 (2985 1460);
PAINT MONO (2985 1460);
FORCEPROP 2 LASTPIN (2975 2150) $PN 32
J 0
(2985 2160);
DISPLAY 0.489362 (2985 2160);
PAINT MONO (2985 2160);
FORCEPROP 2 LASTPIN (2125 2700) $PN 4
J 2
(2115 2710);
DISPLAY 0.489362 (2115 2710);
PAINT MONO (2115 2710);
FORCEPROP 2 LASTPIN (2125 1450) $PN 34
J 2
(2115 1460);
DISPLAY 0.489362 (2115 1460);
PAINT MONO (2115 1460);
FORCEPROP 2 LASTPIN (2125 1950) $PN 39
J 2
(2115 1960);
DISPLAY 0.489362 (2115 1960);
PAINT MONO (2115 1960);
FORCEPROP 2 LASTPIN (2975 2050) $PN 10_19
J 0
(2985 2060);
DISPLAY 0.489362 (2985 2060);
PAINT MONO (2985 2060);
FORCEPROP 2 LASTPIN (2125 1550) $PN 36
J 2
(2115 1560);
DISPLAY 0.489362 (2115 1560);
PAINT MONO (2115 1560);
FORCEPROP 2 LASTPIN (2125 2400) $PN 3
J 2
(2115 2410);
DISPLAY 0.489362 (2115 2410);
PAINT MONO (2115 2410);
FORCEPROP 2 LASTPIN (2975 2700) $PN 25_29
J 0
(2985 2710);
DISPLAY 0.489362 (2985 2710);
PAINT MONO (2985 2710);
FORCEPROP 2 LASTPIN (2975 2650) $PN 30
J 0
(2985 2660);
DISPLAY 0.489362 (2985 2660);
PAINT MONO (2985 2660);
FORCEPROP 2 LASTPIN (2975 1800) $PN 1
J 0
(2985 1810);
DISPLAY 0.489362 (2985 1810);
PAINT MONO (2985 1810);
FORCEPROP 2 LAST PART_TYPE SMLF
J 0
(2275 3050);
DISPLAY 0.638298 (2275 3050);
FORCEPROP 1 LAST MATERIAL IC
J 0
(2275 2775);
DISPLAY 0.489362 (2275 2775);
PAINT SKYBLUE (2275 2775);
FORCEPROP 2 LAST VALUE ISL99390FRZ-TR5935
J 0
(2275 3000);
DISPLAY 0.489362 (2275 3000);
PAINT SKYBLUE (2275 3000);
FORCEPROP 1 LAST PART_NUMBER AL099390004
J 0
(2275 2850);
DISPLAY 0.489362 (2275 2850);
PAINT SKYBLUE (2275 2850);
FORCEPROP 2 LAST CDS_LIB pure_quanta
J 0
(2575 2050);
DISPLAY INVISIBLE (2575 2050);
FORCEPROP 1 LAST CDS_LMAN_SYM_OUTLINE -300,700,250,-650
J 0
(2575 2050);
DISPLAY 0.468085 (2575 2050);
PAINT GREEN (2575 2050);
DISPLAY INVISIBLE (2575 2050);
FORCEPROP 1 LAST NEEDS_NO_SIZE TRUE
J 0
(2575 2050);
DISPLAY 0.723404 (2575 2050);
PAINT GREEN (2575 2050);
DISPLAY INVISIBLE (2575 2050);
FORCEPROP 1 LAST PATH I30
J 0
(2575 2050);
DISPLAY 0.723404 (2575 2050);
PAINT GREEN (2575 2050);
DISPLAY INVISIBLE (2575 2050);
FORCEADD UNIVERSAL_GND..1
(3225 1325);
FORCEPROP 3 LASTPIN (3225 1375) SIG_NAME GND\g
J 0
(3235 1385);
DISPLAY 0.659574 (3235 1385);
PAINT MONO (3235 1385);
DISPLAY INVISIBLE (3235 1385);
FORCEPROP 2 LAST CDS_LIB pure_quanta_power
J 0
(3225 1325);
PAINT MONO (3225 1325);
DISPLAY INVISIBLE (3225 1325);
FORCEPROP 1 LAST PATH I31
J 0
(3300 1325);
DISPLAY 0.872340 (3300 1325);
PAINT AQUA (3300 1325);
DISPLAY INVISIBLE (3300 1325);
FORCEPROP 1 LAST HDL_POWER GND
J 1
(3250 1250);
DISPLAY 0.872340 (3250 1250);
PAINT GREEN (3250 1250);
DISPLAY INVISIBLE (3250 1250);
FORCEADD UNIVERSAL_GND..1
(3225 4075);
FORCEPROP 3 LASTPIN (3225 4125) SIG_NAME GND\g
J 0
(3235 4135);
DISPLAY 0.659574 (3235 4135);
PAINT MONO (3235 4135);
DISPLAY INVISIBLE (3235 4135);
FORCEPROP 2 LAST CDS_LIB pure_quanta_power
J 0
(3225 4075);
PAINT MONO (3225 4075);
DISPLAY INVISIBLE (3225 4075);
FORCEPROP 1 LAST PATH I34
J 0
(3300 4075);
DISPLAY 0.872340 (3300 4075);
PAINT AQUA (3300 4075);
DISPLAY INVISIBLE (3300 4075);
FORCEPROP 1 LAST HDL_POWER GND
J 1
(3250 4000);
DISPLAY 0.872340 (3250 4000);
PAINT GREEN (3250 4000);
DISPLAY INVISIBLE (3250 4000);
FORCEADD ISL99390FRZTR5935..1
(2575 4800);
FORCEPROP 1 LAST LOCATION PU39
J 0
(2275 5675);
DISPLAY 0.489362 (2275 5675);
PAINT SKYBLUE (2275 5675);
FORCEPROP 2 LAST $SEC 1
J 0
(2275 5725);
DISPLAY 0.680851 (2275 5725);
PAINT MONO (2275 5725);
DISPLAY INVISIBLE (2275 5725);
FORCEPROP 2 LAST CDS_SEC 1
J 0
(2325 5800);
DISPLAY 1.021277 (2325 5800);
DISPLAY INVISIBLE (2325 5800);
FORCEPROP 2 LASTPIN (2975 4350) $PN 2
J 0
(2985 4360);
DISPLAY 0.489362 (2985 4360);
PAINT MONO (2985 4360);
FORCEPROP 2 LASTPIN (2975 5150) $PN 33
J 0
(2985 5160);
DISPLAY 0.489362 (2985 5160);
PAINT MONO (2985 5160);
FORCEPROP 2 LASTPIN (2125 4550) $PN 31
J 2
(2115 4560);
DISPLAY 0.489362 (2115 4560);
PAINT MONO (2115 4560);
FORCEPROP 2 LASTPIN (2125 4950) $PN 35
J 2
(2115 4960);
DISPLAY 0.489362 (2115 4960);
PAINT MONO (2115 4960);
FORCEPROP 2 LASTPIN (2975 4500) $PN 6
J 0
(2985 4510);
DISPLAY 0.489362 (2985 4510);
PAINT MONO (2985 4510);
FORCEPROP 2 LASTPIN (2975 4450) $PN 41
J 0
(2985 4460);
DISPLAY 0.489362 (2985 4460);
PAINT MONO (2985 4460);
FORCEPROP 2 LASTPIN (2125 4800) $PN 38
J 2
(2115 4810);
DISPLAY 0.489362 (2115 4810);
PAINT MONO (2115 4810);
FORCEPROP 2 LASTPIN (2125 4500) $PN 37
J 2
(2115 4510);
DISPLAY 0.489362 (2115 4510);
PAINT MONO (2115 4510);
FORCEPROP 2 LASTPIN (2975 4300) $PN 5
J 0
(2985 4310);
DISPLAY 0.489362 (2985 4310);
PAINT MONO (2985 4310);
FORCEPROP 2 LASTPIN (2975 4250) $PN 7_9-20_24
J 0
(2985 4260);
DISPLAY 0.489362 (2985 4260);
PAINT MONO (2985 4260);
FORCEPROP 2 LASTPIN (2975 4200) $PN 40
J 0
(2985 4210);
DISPLAY 0.489362 (2985 4210);
PAINT MONO (2985 4210);
FORCEPROP 2 LASTPIN (2975 4900) $PN 32
J 0
(2985 4910);
DISPLAY 0.489362 (2985 4910);
PAINT MONO (2985 4910);
FORCEPROP 2 LASTPIN (2125 5450) $PN 4
J 2
(2115 5460);
DISPLAY 0.489362 (2115 5460);
PAINT MONO (2115 5460);
FORCEPROP 2 LASTPIN (2125 4200) $PN 34
J 2
(2115 4210);
DISPLAY 0.489362 (2115 4210);
PAINT MONO (2115 4210);
FORCEPROP 2 LASTPIN (2125 4700) $PN 39
J 2
(2115 4710);
DISPLAY 0.489362 (2115 4710);
PAINT MONO (2115 4710);
FORCEPROP 2 LASTPIN (2975 4800) $PN 10_19
J 0
(2985 4810);
DISPLAY 0.489362 (2985 4810);
PAINT MONO (2985 4810);
FORCEPROP 2 LASTPIN (2125 4300) $PN 36
J 2
(2115 4310);
DISPLAY 0.489362 (2115 4310);
PAINT MONO (2115 4310);
FORCEPROP 2 LASTPIN (2125 5150) $PN 3
J 2
(2115 5160);
DISPLAY 0.489362 (2115 5160);
PAINT MONO (2115 5160);
FORCEPROP 2 LASTPIN (2975 5450) $PN 25_29
J 0
(2985 5460);
DISPLAY 0.489362 (2985 5460);
PAINT MONO (2985 5460);
FORCEPROP 2 LASTPIN (2975 5400) $PN 30
J 0
(2985 5410);
DISPLAY 0.489362 (2985 5410);
PAINT MONO (2985 5410);
FORCEPROP 2 LASTPIN (2975 4550) $PN 1
J 0
(2985 4560);
DISPLAY 0.489362 (2985 4560);
PAINT MONO (2985 4560);
FORCEPROP 2 LAST PART_TYPE SMLF
J 0
(2275 5825);
DISPLAY 0.638298 (2275 5825);
FORCEPROP 1 LAST MATERIAL IC
J 0
(2275 5525);
DISPLAY 0.489362 (2275 5525);
PAINT SKYBLUE (2275 5525);
FORCEPROP 2 LAST VALUE ISL99390FRZ-TR5935
J 0
(2275 5775);
DISPLAY 0.489362 (2275 5775);
PAINT SKYBLUE (2275 5775);
FORCEPROP 1 LAST PART_NUMBER AL099390004
J 0
(2275 5600);
DISPLAY 0.489362 (2275 5600);
PAINT SKYBLUE (2275 5600);
FORCEPROP 1 LAST NEEDS_NO_SIZE TRUE
J 0
(2575 4800);
DISPLAY 0.723404 (2575 4800);
PAINT GREEN (2575 4800);
DISPLAY INVISIBLE (2575 4800);
FORCEPROP 1 LAST CDS_LMAN_SYM_OUTLINE -300,700,250,-650
J 0
(2575 4800);
DISPLAY 0.468085 (2575 4800);
PAINT GREEN (2575 4800);
DISPLAY INVISIBLE (2575 4800);
FORCEPROP 2 LAST CDS_LIB pure_quanta
J 0
(2575 4800);
DISPLAY INVISIBLE (2575 4800);
FORCEPROP 1 LAST PATH I35
J 0
(2575 4800);
DISPLAY 0.723404 (2575 4800);
PAINT GREEN (2575 4800);
DISPLAY INVISIBLE (2575 4800);
FORCEADD Q_CAP..1
(3900 2975);
FORCEPROP 1 LAST LOCATION PC441_2
J 0
(3950 3125);
DISPLAY 0.489362 (3950 3125);
PAINT SKYBLUE (3950 3125);
FORCEPROP 0 LAST $SEC 1
J 0
(3950 3175);
DISPLAY 0.680851 (3950 3175);
PAINT MONO (3950 3175);
DISPLAY INVISIBLE (3950 3175);
FORCEPROP 0 LAST CDS_SEC 1
J 0
(3950 3175);
DISPLAY 1.021277 (3950 3175);
DISPLAY INVISIBLE (3950 3175);
FORCEPROP 1 LASTPIN (3900 3075) $PN 1
J 0
(3910 3055);
DISPLAY 0.489362 (3910 3055);
PAINT MONO (3910 3055);
FORCEPROP 1 LASTPIN (3900 2875) $PN 2
J 0
(3910 2855);
DISPLAY 0.489362 (3910 2855);
PAINT MONO (3910 2855);
FORCEPROP 1 LAST MATERIAL X6S
J 0
(3950 2925);
DISPLAY 0.489362 (3950 2925);
PAINT SKYBLUE (3950 2925);
FORCEPROP 1 LAST TOLERANCE 10%
J 0
(3950 2975);
DISPLAY 0.489362 (3950 2975);
PAINT SKYBLUE (3950 2975);
FORCEPROP 1 LAST VALUE 1UF
J 0
(3950 3075);
DISPLAY 0.489362 (3950 3075);
PAINT SKYBLUE (3950 3075);
FORCEPROP 1 LAST PART_NUMBER CH5104KEB02
J 0
(3950 2825);
DISPLAY 0.489362 (3950 2825);
PAINT SKYBLUE (3950 2825);
FORCEPROP 1 LAST VOLTAGE 25V
J 0
(3950 3025);
DISPLAY 0.489362 (3950 3025);
PAINT SKYBLUE (3950 3025);
FORCEPROP 1 LAST PACK_TYPE C0402
J 0
(3950 2875);
DISPLAY 0.489362 (3950 2875);
PAINT SKYBLUE (3950 2875);
FORCEPROP 2 LAST CDS_LIB pure_quanta
J 0
(3900 2975);
DISPLAY INVISIBLE (3900 2975);
FORCEPROP 1 LAST PATH I39
J 0
(3950 3125);
DISPLAY 0.978723 (3950 3125);
PAINT WHITE (3950 3125);
DISPLAY INVISIBLE (3950 3125);
FORCEADD OFFPAGE..1
(1025 1450);
FORCEPROP 2 LAST $XR0 193 
J 0
(773 1450);
DISPLAY 0.638298 (773 1450);
PAINT MONO (773 1450);
FORCEPROP 2 LAST CDS_LIB standard
J 0
(1025 1450);
DISPLAY INVISIBLE (1025 1450);
FORCEPROP 1 LAST OFFPAGE TRUE
J 0
(1350 1325);
DISPLAY 0.872340 (1350 1325);
PAINT GREEN (1350 1325);
DISPLAY INVISIBLE (1350 1325);
FORCEPROP 1 LAST COMMENT_BODY TRUE
J 0
(1150 1350);
DISPLAY 0.872340 (1150 1350);
PAINT GREEN (1150 1350);
DISPLAY INVISIBLE (1150 1350);
FORCEPROP 2 LAST PATH I4
J 0
(600 1500);
DISPLAY 1.021277 (600 1500);
DISPLAY INVISIBLE (600 1500);
FORCEADD Q_CAP..1
(4300 2975);
FORCEPROP 1 LAST LOCATION PC443_2
J 0
(4350 3125);
DISPLAY 0.489362 (4350 3125);
PAINT SKYBLUE (4350 3125);
FORCEPROP 0 LAST $SEC 1
J 0
(4350 3175);
DISPLAY 0.680851 (4350 3175);
PAINT MONO (4350 3175);
DISPLAY INVISIBLE (4350 3175);
FORCEPROP 0 LAST CDS_SEC 1
J 0
(4350 3175);
DISPLAY 1.021277 (4350 3175);
DISPLAY INVISIBLE (4350 3175);
FORCEPROP 1 LASTPIN (4300 3075) $PN 1
J 0
(4310 3055);
DISPLAY 0.489362 (4310 3055);
PAINT MONO (4310 3055);
FORCEPROP 1 LASTPIN (4300 2875) $PN 2
J 0
(4310 2855);
DISPLAY 0.489362 (4310 2855);
PAINT MONO (4310 2855);
FORCEPROP 1 LAST MATERIAL X6S
J 0
(4350 2925);
DISPLAY 0.489362 (4350 2925);
PAINT SKYBLUE (4350 2925);
FORCEPROP 1 LAST TOLERANCE 10%
J 0
(4350 2975);
DISPLAY 0.489362 (4350 2975);
PAINT SKYBLUE (4350 2975);
FORCEPROP 1 LAST VALUE 10UF
J 0
(4350 3075);
DISPLAY 0.489362 (4350 3075);
PAINT SKYBLUE (4350 3075);
FORCEPROP 1 LAST PART_NUMBER CH6104KEA00
J 0
(4350 2825);
DISPLAY 0.489362 (4350 2825);
PAINT SKYBLUE (4350 2825);
FORCEPROP 1 LAST VOLTAGE 25V
J 0
(4350 3025);
DISPLAY 0.489362 (4350 3025);
PAINT SKYBLUE (4350 3025);
FORCEPROP 1 LAST PACK_TYPE C0805
J 0
(4350 2875);
DISPLAY 0.489362 (4350 2875);
PAINT SKYBLUE (4350 2875);
FORCEPROP 2 LAST CDS_LIB pure_quanta
J 0
(4300 2975);
DISPLAY INVISIBLE (4300 2975);
FORCEPROP 1 LAST PATH I41
J 0
(4350 3125);
DISPLAY 0.978723 (4350 3125);
PAINT WHITE (4350 3125);
DISPLAY INVISIBLE (4350 3125);
FORCEADD Q_CAP..1
(4700 2975);
FORCEPROP 1 LAST LOCATION PC446_2
J 0
(4750 3125);
DISPLAY 0.489362 (4750 3125);
PAINT SKYBLUE (4750 3125);
FORCEPROP 0 LAST $SEC 1
J 0
(4750 3175);
DISPLAY 0.680851 (4750 3175);
PAINT MONO (4750 3175);
DISPLAY INVISIBLE (4750 3175);
FORCEPROP 0 LAST CDS_SEC 1
J 0
(4750 3175);
DISPLAY 1.021277 (4750 3175);
DISPLAY INVISIBLE (4750 3175);
FORCEPROP 1 LASTPIN (4700 3075) $PN 1
J 0
(4710 3055);
DISPLAY 0.489362 (4710 3055);
PAINT MONO (4710 3055);
FORCEPROP 1 LASTPIN (4700 2875) $PN 2
J 0
(4710 2855);
DISPLAY 0.489362 (4710 2855);
PAINT MONO (4710 2855);
FORCEPROP 1 LAST MATERIAL X6S
J 0
(4750 2925);
DISPLAY 0.489362 (4750 2925);
PAINT SKYBLUE (4750 2925);
FORCEPROP 1 LAST TOLERANCE 10%
J 0
(4750 2975);
DISPLAY 0.489362 (4750 2975);
PAINT SKYBLUE (4750 2975);
FORCEPROP 1 LAST VALUE 10UF
J 0
(4750 3075);
DISPLAY 0.489362 (4750 3075);
PAINT SKYBLUE (4750 3075);
FORCEPROP 1 LAST PART_NUMBER CH6104KEA00
J 0
(4750 2825);
DISPLAY 0.489362 (4750 2825);
PAINT SKYBLUE (4750 2825);
FORCEPROP 1 LAST VOLTAGE 25V
J 0
(4750 3025);
DISPLAY 0.489362 (4750 3025);
PAINT SKYBLUE (4750 3025);
FORCEPROP 1 LAST PACK_TYPE C0805
J 0
(4750 2875);
DISPLAY 0.489362 (4750 2875);
PAINT SKYBLUE (4750 2875);
FORCEPROP 2 LAST CDS_LIB pure_quanta
J 0
(4700 2975);
DISPLAY INVISIBLE (4700 2975);
FORCEPROP 1 LAST PATH I42
J 0
(4750 3125);
DISPLAY 0.978723 (4750 3125);
PAINT WHITE (4750 3125);
DISPLAY INVISIBLE (4750 3125);
FORCEADD UNIVERSAL_GND..1
(5175 2625);
FORCEPROP 3 LASTPIN (5175 2675) SIG_NAME GND\g
J 0
(5185 2685);
DISPLAY 0.659574 (5185 2685);
PAINT MONO (5185 2685);
DISPLAY INVISIBLE (5185 2685);
FORCEPROP 2 LAST CDS_LIB pure_quanta_power
J 0
(5175 2625);
PAINT MONO (5175 2625);
DISPLAY INVISIBLE (5175 2625);
FORCEPROP 1 LAST PATH I44
J 0
(5250 2625);
DISPLAY 0.872340 (5250 2625);
PAINT AQUA (5250 2625);
DISPLAY INVISIBLE (5250 2625);
FORCEPROP 1 LAST HDL_POWER GND
J 1
(5200 2550);
DISPLAY 0.872340 (5200 2550);
PAINT GREEN (5200 2550);
DISPLAY INVISIBLE (5200 2550);
FORCEADD Q_CAP..1
(3650 5700);
FORCEPROP 1 LAST LOCATION PC440_1
J 0
(3700 5850);
DISPLAY 0.489362 (3700 5850);
PAINT SKYBLUE (3700 5850);
FORCEPROP 0 LAST $SEC 1
J 0
(3700 5900);
DISPLAY 0.680851 (3700 5900);
PAINT MONO (3700 5900);
DISPLAY INVISIBLE (3700 5900);
FORCEPROP 0 LAST CDS_SEC 1
J 0
(3700 5900);
DISPLAY 1.021277 (3700 5900);
DISPLAY INVISIBLE (3700 5900);
FORCEPROP 1 LASTPIN (3650 5800) $PN 1
J 0
(3660 5780);
DISPLAY 0.489362 (3660 5780);
PAINT MONO (3660 5780);
FORCEPROP 1 LASTPIN (3650 5600) $PN 2
J 0
(3660 5580);
DISPLAY 0.489362 (3660 5580);
PAINT MONO (3660 5580);
FORCEPROP 1 LAST MATERIAL X6S
J 0
(3700 5650);
DISPLAY 0.489362 (3700 5650);
PAINT SKYBLUE (3700 5650);
FORCEPROP 1 LAST TOLERANCE 10%
J 0
(3700 5700);
DISPLAY 0.489362 (3700 5700);
PAINT SKYBLUE (3700 5700);
FORCEPROP 1 LAST VALUE 1UF
J 0
(3700 5800);
DISPLAY 0.489362 (3700 5800);
PAINT SKYBLUE (3700 5800);
FORCEPROP 1 LAST PART_NUMBER CH5104KEB02
J 0
(3700 5550);
DISPLAY 0.489362 (3700 5550);
PAINT SKYBLUE (3700 5550);
FORCEPROP 1 LAST VOLTAGE 25V
J 0
(3700 5750);
DISPLAY 0.489362 (3700 5750);
PAINT SKYBLUE (3700 5750);
FORCEPROP 1 LAST PACK_TYPE C0402
J 0
(3700 5600);
DISPLAY 0.489362 (3700 5600);
PAINT SKYBLUE (3700 5600);
FORCEPROP 2 LAST CDS_LIB pure_quanta
J 0
(3650 5700);
DISPLAY INVISIBLE (3650 5700);
FORCEPROP 1 LAST PATH I50
J 0
(3700 5850);
DISPLAY 0.978723 (3700 5850);
PAINT WHITE (3700 5850);
DISPLAY INVISIBLE (3700 5850);
FORCEADD Q_RES..1
(3900 5150);
FORCEPROP 1 LAST LOCATION PR279
J 0
(3850 5200);
DISPLAY 0.489362 (3850 5200);
PAINT SKYBLUE (3850 5200);
FORCEPROP 2 LAST $SEC 1
J 0
(3850 5350);
DISPLAY 0.680851 (3850 5350);
PAINT MONO (3850 5350);
DISPLAY INVISIBLE (3850 5350);
FORCEPROP 2 LAST CDS_SEC 1
J 0
(3850 5350);
DISPLAY 1.021277 (3850 5350);
DISPLAY INVISIBLE (3850 5350);
FORCEPROP 1 LASTPIN (3800 5150) $PN 1
J 0
(3812 5162);
DISPLAY 0.489362 (3812 5162);
FORCEPROP 1 LASTPIN (4000 5150) $PN 2
J 0
(3962 5162);
DISPLAY 0.489362 (3962 5162);
FORCEPROP 1 LAST PACK_TYPE 0402LF
J 0
(3975 5050);
DISPLAY 0.489362 (3975 5050);
PAINT SKYBLUE (3975 5050);
FORCEPROP 1 LAST TOLERANCE 1%
J 0
(3750 5050);
DISPLAY 0.489362 (3750 5050);
PAINT SKYBLUE (3750 5050);
FORCEPROP 1 LAST MATERIAL CHIP
J 0
(4000 5100);
DISPLAY 0.489362 (4000 5100);
PAINT SKYBLUE (4000 5100);
FORCEPROP 1 LAST WATTAGE 1/16W
J 2
(4125 5175);
DISPLAY 0.489362 (4125 5175);
PAINT SKYBLUE (4125 5175);
FORCEPROP 1 LAST VALUE 4.7
J 2
(3775 5175);
DISPLAY 0.489362 (3775 5175);
PAINT SKYBLUE (3775 5175);
FORCEPROP 1 LAST PART_NUMBER CS-4702FB19
J 0
(3625 5100);
DISPLAY 0.489362 (3625 5100);
PAINT SKYBLUE (3625 5100);
FORCEPROP 1 LAST PATH I51
J 0
(3850 5300);
DISPLAY 0.978723 (3850 5300);
PAINT WHITE (3850 5300);
DISPLAY INVISIBLE (3850 5300);
FORCEPROP 2 LAST CDS_LIB pure_quanta
J 0
(3900 5150);
PAINT MONO (3900 5150);
DISPLAY INVISIBLE (3900 5150);
FORCEADD Q_CAP..1
(3975 5700);
FORCEPROP 1 LAST LOCATION PC442_1
J 0
(4025 5850);
DISPLAY 0.489362 (4025 5850);
PAINT SKYBLUE (4025 5850);
FORCEPROP 0 LAST $SEC 1
J 0
(4025 5900);
DISPLAY 0.680851 (4025 5900);
PAINT MONO (4025 5900);
DISPLAY INVISIBLE (4025 5900);
FORCEPROP 0 LAST CDS_SEC 1
J 0
(4025 5900);
DISPLAY 1.021277 (4025 5900);
DISPLAY INVISIBLE (4025 5900);
FORCEPROP 1 LASTPIN (3975 5800) $PN 1
J 0
(3985 5780);
DISPLAY 0.489362 (3985 5780);
PAINT MONO (3985 5780);
FORCEPROP 1 LASTPIN (3975 5600) $PN 2
J 0
(3985 5580);
DISPLAY 0.489362 (3985 5580);
PAINT MONO (3985 5580);
FORCEPROP 1 LAST MATERIAL X6S
J 0
(4025 5650);
DISPLAY 0.489362 (4025 5650);
PAINT SKYBLUE (4025 5650);
FORCEPROP 1 LAST TOLERANCE 10%
J 0
(4025 5700);
DISPLAY 0.489362 (4025 5700);
PAINT SKYBLUE (4025 5700);
FORCEPROP 1 LAST VALUE 10UF
J 0
(4025 5800);
DISPLAY 0.489362 (4025 5800);
PAINT SKYBLUE (4025 5800);
FORCEPROP 1 LAST PART_NUMBER CH6104KEA00
J 0
(4025 5550);
DISPLAY 0.489362 (4025 5550);
PAINT SKYBLUE (4025 5550);
FORCEPROP 1 LAST VOLTAGE 25V
J 0
(4025 5750);
DISPLAY 0.489362 (4025 5750);
PAINT SKYBLUE (4025 5750);
FORCEPROP 1 LAST PACK_TYPE C0805
J 0
(4025 5600);
DISPLAY 0.489362 (4025 5600);
PAINT SKYBLUE (4025 5600);
FORCEPROP 2 LAST CDS_LIB pure_quanta
J 0
(3975 5700);
DISPLAY INVISIBLE (3975 5700);
FORCEPROP 1 LAST PATH I52
J 0
(4025 5850);
DISPLAY 0.978723 (4025 5850);
PAINT WHITE (4025 5850);
DISPLAY INVISIBLE (4025 5850);
FORCEADD Q_CAP..1
(4300 5700);
FORCEPROP 1 LAST LOCATION PC444_1
J 0
(4350 5850);
DISPLAY 0.489362 (4350 5850);
PAINT SKYBLUE (4350 5850);
FORCEPROP 0 LAST $SEC 1
J 0
(4350 5900);
DISPLAY 0.680851 (4350 5900);
PAINT MONO (4350 5900);
DISPLAY INVISIBLE (4350 5900);
FORCEPROP 0 LAST CDS_SEC 1
J 0
(4350 5900);
DISPLAY 1.021277 (4350 5900);
DISPLAY INVISIBLE (4350 5900);
FORCEPROP 1 LASTPIN (4300 5800) $PN 1
J 0
(4310 5780);
DISPLAY 0.489362 (4310 5780);
PAINT MONO (4310 5780);
FORCEPROP 1 LASTPIN (4300 5600) $PN 2
J 0
(4310 5580);
DISPLAY 0.489362 (4310 5580);
PAINT MONO (4310 5580);
FORCEPROP 1 LAST MATERIAL X6S
J 0
(4350 5650);
DISPLAY 0.489362 (4350 5650);
PAINT SKYBLUE (4350 5650);
FORCEPROP 1 LAST TOLERANCE 10%
J 0
(4350 5700);
DISPLAY 0.489362 (4350 5700);
PAINT SKYBLUE (4350 5700);
FORCEPROP 1 LAST VALUE 10UF
J 0
(4350 5800);
DISPLAY 0.489362 (4350 5800);
PAINT SKYBLUE (4350 5800);
FORCEPROP 1 LAST PART_NUMBER CH6104KEA00
J 0
(4350 5550);
DISPLAY 0.489362 (4350 5550);
PAINT SKYBLUE (4350 5550);
FORCEPROP 1 LAST VOLTAGE 25V
J 0
(4350 5750);
DISPLAY 0.489362 (4350 5750);
PAINT SKYBLUE (4350 5750);
FORCEPROP 1 LAST PACK_TYPE C0805
J 0
(4350 5600);
DISPLAY 0.489362 (4350 5600);
PAINT SKYBLUE (4350 5600);
FORCEPROP 2 LAST CDS_LIB pure_quanta
J 0
(4300 5700);
DISPLAY INVISIBLE (4300 5700);
FORCEPROP 1 LAST PATH I56
J 0
(4350 5850);
DISPLAY 0.978723 (4350 5850);
PAINT WHITE (4350 5850);
DISPLAY INVISIBLE (4350 5850);
FORCEADD UNIVERSAL_GND..1
(4575 5325);
FORCEPROP 3 LASTPIN (4575 5375) SIG_NAME GND\g
J 0
(4585 5385);
DISPLAY 0.659574 (4585 5385);
PAINT MONO (4585 5385);
DISPLAY INVISIBLE (4585 5385);
FORCEPROP 2 LAST CDS_LIB pure_quanta_power
J 0
(4575 5325);
PAINT MONO (4575 5325);
DISPLAY INVISIBLE (4575 5325);
FORCEPROP 1 LAST PATH I57
J 0
(4650 5325);
DISPLAY 0.872340 (4650 5325);
PAINT AQUA (4650 5325);
DISPLAY INVISIBLE (4650 5325);
FORCEPROP 1 LAST HDL_POWER GND
J 1
(4600 5250);
DISPLAY 0.872340 (4600 5250);
PAINT GREEN (4600 5250);
DISPLAY INVISIBLE (4600 5250);
FORCEADD OFFPAGE..5
(1025 2050);
FORCEPROP 2 LAST $XR0 193 
J 0
(770 2050);
DISPLAY 0.638298 (770 2050);
PAINT MONO (770 2050);
FORCEPROP 2 LAST CDS_LIB standard
J 0
(1025 2050);
DISPLAY INVISIBLE (1025 2050);
FORCEPROP 1 LAST OFFPAGE TRUE
J 0
(1350 1925);
DISPLAY 0.872340 (1350 1925);
PAINT GREEN (1350 1925);
DISPLAY INVISIBLE (1350 1925);
FORCEPROP 1 LAST COMMENT_BODY TRUE
J 0
(1125 1975);
DISPLAY 0.872340 (1125 1975);
PAINT GREEN (1125 1975);
DISPLAY INVISIBLE (1125 1975);
FORCEPROP 2 LAST PATH I6
J 0
(775 2100);
DISPLAY 1.021277 (775 2100);
DISPLAY INVISIBLE (775 2100);
FORCEADD Q_CAP..1
(7400 1850);
FORCEPROP 1 LAST LOCATION PC458_2
J 0
(7450 1975);
DISPLAY 0.489362 (7450 1975);
PAINT SKYBLUE (7450 1975);
FORCEPROP 0 LAST $SEC 1
J 0
(7450 2025);
DISPLAY 0.680851 (7450 2025);
PAINT MONO (7450 2025);
DISPLAY INVISIBLE (7450 2025);
FORCEPROP 0 LAST CDS_SEC 1
J 0
(7450 2025);
DISPLAY 1.021277 (7450 2025);
DISPLAY INVISIBLE (7450 2025);
FORCEPROP 1 LASTPIN (7400 1950) $PN 1
J 0
(7410 1930);
DISPLAY 0.489362 (7410 1930);
PAINT MONO (7410 1930);
FORCEPROP 1 LASTPIN (7400 1750) $PN 2
J 0
(7410 1730);
DISPLAY 0.489362 (7410 1730);
PAINT MONO (7410 1730);
FORCEPROP 1 LAST MATERIAL X6S
J 0
(7450 1775);
DISPLAY 0.489362 (7450 1775);
PAINT SKYBLUE (7450 1775);
FORCEPROP 1 LAST TOLERANCE 20%
J 0
(7450 1825);
DISPLAY 0.489362 (7450 1825);
PAINT SKYBLUE (7450 1825);
FORCEPROP 1 LAST VALUE 22UF
J 0
(7450 1925);
DISPLAY 0.489362 (7450 1925);
PAINT SKYBLUE (7450 1925);
FORCEPROP 1 LAST PART_NUMBER TMP_QCH622KMEA01
J 0
(7450 1675);
DISPLAY 0.489362 (7450 1675);
PAINT SKYBLUE (7450 1675);
FORCEPROP 1 LAST VOLTAGE 4V
J 0
(7450 1875);
DISPLAY 0.489362 (7450 1875);
PAINT SKYBLUE (7450 1875);
FORCEPROP 1 LAST PACK_TYPE 0805
J 0
(7450 1725);
DISPLAY 0.489362 (7450 1725);
PAINT SKYBLUE (7450 1725);
FORCEPROP 2 LAST CDS_LIB pure_quanta
J 0
(7400 1850);
DISPLAY INVISIBLE (7400 1850);
FORCEPROP 1 LAST PATH I60
J 0
(7450 2000);
DISPLAY 0.978723 (7450 2000);
PAINT WHITE (7450 2000);
DISPLAY INVISIBLE (7450 2000);
FORCEADD Q_CAP..1
(7825 1850);
FORCEPROP 1 LAST LOCATION PC460_2
J 0
(7875 1975);
DISPLAY 0.489362 (7875 1975);
PAINT SKYBLUE (7875 1975);
FORCEPROP 0 LAST $SEC 1
J 0
(7875 2025);
DISPLAY 0.680851 (7875 2025);
PAINT MONO (7875 2025);
DISPLAY INVISIBLE (7875 2025);
FORCEPROP 0 LAST CDS_SEC 1
J 0
(7875 2025);
DISPLAY 1.021277 (7875 2025);
DISPLAY INVISIBLE (7875 2025);
FORCEPROP 1 LASTPIN (7825 1950) $PN 1
J 0
(7835 1930);
DISPLAY 0.489362 (7835 1930);
PAINT MONO (7835 1930);
FORCEPROP 1 LASTPIN (7825 1750) $PN 2
J 0
(7835 1730);
DISPLAY 0.489362 (7835 1730);
PAINT MONO (7835 1730);
FORCEPROP 1 LAST MATERIAL X6S
J 0
(7875 1775);
DISPLAY 0.489362 (7875 1775);
PAINT SKYBLUE (7875 1775);
FORCEPROP 1 LAST TOLERANCE 20%
J 0
(7875 1825);
DISPLAY 0.489362 (7875 1825);
PAINT SKYBLUE (7875 1825);
FORCEPROP 1 LAST VALUE 22UF
J 0
(7875 1925);
DISPLAY 0.489362 (7875 1925);
PAINT SKYBLUE (7875 1925);
FORCEPROP 1 LAST PART_NUMBER TMP_QCH622KMEA01
J 0
(7875 1675);
DISPLAY 0.489362 (7875 1675);
PAINT SKYBLUE (7875 1675);
FORCEPROP 1 LAST VOLTAGE 4V
J 0
(7875 1875);
DISPLAY 0.489362 (7875 1875);
PAINT SKYBLUE (7875 1875);
FORCEPROP 1 LAST PACK_TYPE 0805
J 0
(7875 1725);
DISPLAY 0.489362 (7875 1725);
PAINT SKYBLUE (7875 1725);
FORCEPROP 2 LAST CDS_LIB pure_quanta
J 0
(7825 1850);
DISPLAY INVISIBLE (7825 1850);
FORCEPROP 1 LAST PATH I61
J 0
(7875 2000);
DISPLAY 0.978723 (7875 2000);
PAINT WHITE (7875 2000);
DISPLAY INVISIBLE (7875 2000);
FORCEADD VCC_CORE..1
(7825 2200);
FORCEPROP 3 LASTPIN (7825 2150) SIG_NAME PVDDIO_P1\g
J 0
(7835 2160);
DISPLAY 0.659574 (7835 2160);
PAINT MONO (7835 2160);
DISPLAY INVISIBLE (7835 2160);
FORCEPROP 1 LAST HDL_POWER PVDDIO_P1
J 1
(7825 2250);
DISPLAY 0.489362 (7825 2250);
PAINT GREEN (7825 2250);
FORCEPROP 2 LAST CDS_LIB pure_quanta_power
J 0
(7825 2200);
DISPLAY INVISIBLE (7825 2200);
FORCEPROP 1 LAST PATH I64
J 0
(7875 2225);
DISPLAY 0.872340 (7875 2225);
PAINT AQUA (7875 2225);
DISPLAY INVISIBLE (7875 2225);
FORCEADD Q_CAPP..1
(7325 3075);
FORCEPROP 1 LAST LOCATION PC452
J 0
(7375 3225);
DISPLAY 0.489362 (7375 3225);
PAINT SKYBLUE (7375 3225);
FORCEPROP 0 LAST $SEC 1
J 0
(7375 3275);
DISPLAY 0.680851 (7375 3275);
PAINT MONO (7375 3275);
DISPLAY INVISIBLE (7375 3275);
FORCEPROP 0 LAST CDS_SEC 1
J 0
(7375 3275);
DISPLAY 1.021277 (7375 3275);
DISPLAY INVISIBLE (7375 3275);
FORCEPROP 1 LASTPIN (7325 3175) $PN 1
J 0
(7335 3160);
DISPLAY 0.489362 (7335 3160);
PAINT MONO (7335 3160);
FORCEPROP 1 LASTPIN (7325 2975) $PN 2
J 0
(7335 2960);
DISPLAY 0.489362 (7335 2960);
PAINT MONO (7335 2960);
FORCEPROP 1 LAST MATERIAL SPCAP
J 0
(7375 3025);
DISPLAY 0.489362 (7375 3025);
PAINT SKYBLUE (7375 3025);
FORCEPROP 1 LAST TOLERANCE 20%
J 0
(7375 3125);
DISPLAY 0.489362 (7375 3125);
PAINT SKYBLUE (7375 3125);
FORCEPROP 1 LAST VALUE 470UF
J 0
(7375 3175);
DISPLAY 0.489362 (7375 3175);
PAINT SKYBLUE (7375 3175);
FORCEPROP 1 LAST PART_NUMBER CH747LM8825
J 0
(7375 2925);
DISPLAY 0.489362 (7375 2925);
PAINT SKYBLUE (7375 2925);
FORCEPROP 1 LAST VOLTAGE 2.5V
J 0
(7375 3075);
DISPLAY 0.489362 (7375 3075);
PAINT SKYBLUE (7375 3075);
FORCEPROP 1 LAST PACK_TYPE SMLF
J 0
(7375 2975);
DISPLAY 0.489362 (7375 2975);
PAINT SKYBLUE (7375 2975);
FORCEPROP 2 LAST CDS_LIB pure_quanta
J 0
(7325 3075);
DISPLAY INVISIBLE (7325 3075);
FORCEPROP 1 LAST PATH I66
J 0
(7375 3225);
DISPLAY 0.978723 (7375 3225);
DISPLAY INVISIBLE (7375 3225);
FORCEADD UNIVERSAL_GND..1
(7725 2725);
FORCEPROP 3 LASTPIN (7725 2775) SIG_NAME GND\g
J 0
(7735 2785);
DISPLAY 0.659574 (7735 2785);
PAINT MONO (7735 2785);
DISPLAY INVISIBLE (7735 2785);
FORCEPROP 2 LAST CDS_LIB pure_quanta_power
J 0
(7725 2725);
PAINT MONO (7725 2725);
DISPLAY INVISIBLE (7725 2725);
FORCEPROP 1 LAST PATH I67
J 0
(7800 2725);
DISPLAY 0.872340 (7800 2725);
PAINT AQUA (7800 2725);
DISPLAY INVISIBLE (7800 2725);
FORCEPROP 1 LAST HDL_POWER GND
J 1
(7750 2650);
DISPLAY 0.872340 (7750 2650);
PAINT GREEN (7750 2650);
DISPLAY INVISIBLE (7750 2650);
FORCEADD Q_CAPP..1
(7725 3075);
FORCEPROP 1 LAST LOCATION PC455
J 0
(7800 3225);
DISPLAY 0.489362 (7800 3225);
PAINT SKYBLUE (7800 3225);
FORCEPROP 2 LAST $SEC 1
J 0
(7775 3275);
DISPLAY 0.680851 (7775 3275);
PAINT MONO (7775 3275);
DISPLAY INVISIBLE (7775 3275);
FORCEPROP 2 LAST CDS_SEC 1
J 0
(7775 3275);
DISPLAY 1.021277 (7775 3275);
DISPLAY INVISIBLE (7775 3275);
FORCEPROP 1 LASTPIN (7725 3175) $PN 1
J 0
(7735 3160);
DISPLAY 0.489362 (7735 3160);
PAINT MONO (7735 3160);
FORCEPROP 1 LASTPIN (7725 2975) $PN 2
J 0
(7735 2960);
DISPLAY 0.489362 (7735 2960);
PAINT MONO (7735 2960);
FORCEPROP 1 LAST MATERIAL EMPTY
J 0
(7800 3025);
DISPLAY 0.489362 (7800 3025);
PAINT RED (7800 3025);
FORCEPROP 1 LAST TOLERANCE 20%
J 0
(7800 3125);
DISPLAY 0.489362 (7800 3125);
PAINT SKYBLUE (7800 3125);
FORCEPROP 1 LAST VALUE 470UF
J 0
(7800 3175);
DISPLAY 0.489362 (7800 3175);
PAINT SKYBLUE (7800 3175);
FORCEPROP 1 LAST PART_NUMBER CH747LM8825
J 0
(7800 2925);
DISPLAY 0.489362 (7800 2925);
PAINT SKYBLUE (7800 2925);
FORCEPROP 1 LAST VOLTAGE 2.5V
J 0
(7800 3075);
DISPLAY 0.489362 (7800 3075);
PAINT SKYBLUE (7800 3075);
FORCEPROP 1 LAST PACK_TYPE SMLF
J 0
(7800 2975);
DISPLAY 0.489362 (7800 2975);
PAINT SKYBLUE (7800 2975);
FORCEPROP 2 LAST CDS_LIB pure_quanta
J 0
(7725 3075);
DISPLAY INVISIBLE (7725 3075);
FORCEPROP 1 LAST PATH I68
J 0
(7775 3225);
DISPLAY 0.978723 (7775 3225);
DISPLAY INVISIBLE (7775 3225);
FORCEADD VCC_CORE..1
(7725 3400);
FORCEPROP 3 LASTPIN (7725 3350) SIG_NAME PVDDIO_P1\g
J 0
(7735 3360);
DISPLAY 0.659574 (7735 3360);
PAINT MONO (7735 3360);
DISPLAY INVISIBLE (7735 3360);
FORCEPROP 1 LAST HDL_POWER PVDDIO_P1
J 1
(7725 3450);
DISPLAY 0.489362 (7725 3450);
PAINT GREEN (7725 3450);
FORCEPROP 2 LAST CDS_LIB pure_quanta_power
J 0
(7725 3400);
DISPLAY INVISIBLE (7725 3400);
FORCEPROP 1 LAST PATH I69
J 0
(7775 3425);
DISPLAY 0.872340 (7775 3425);
PAINT AQUA (7775 3425);
DISPLAY INVISIBLE (7775 3425);
FORCEADD OFFPAGE..1
(1025 1950);
FORCEPROP 2 LAST $XR5 199 
J 0
(173 1950);
DISPLAY 0.638298 (173 1950);
PAINT MONO (173 1950);
FORCEPROP 2 LAST $XR4 198 
J 0
(293 1950);
DISPLAY 0.638298 (293 1950);
PAINT MONO (293 1950);
FORCEPROP 2 LAST $XR3 196 
J 0
(413 1950);
DISPLAY 0.638298 (413 1950);
PAINT MONO (413 1950);
FORCEPROP 2 LAST $XR2 195 
J 0
(533 1950);
DISPLAY 0.638298 (533 1950);
PAINT MONO (533 1950);
FORCEPROP 2 LAST $XR1 194 
J 0
(653 1950);
DISPLAY 0.638298 (653 1950);
PAINT MONO (653 1950);
FORCEPROP 2 LAST $XR0 193 
J 0
(773 1950);
DISPLAY 0.638298 (773 1950);
PAINT MONO (773 1950);
FORCEPROP 2 LAST CDS_LIB standard
J 0
(1025 1950);
DISPLAY INVISIBLE (1025 1950);
FORCEPROP 1 LAST OFFPAGE TRUE
J 0
(1350 1825);
DISPLAY 0.872340 (1350 1825);
PAINT GREEN (1350 1825);
DISPLAY INVISIBLE (1350 1825);
FORCEPROP 1 LAST COMMENT_BODY TRUE
J 0
(1150 1850);
DISPLAY 0.872340 (1150 1850);
PAINT GREEN (1150 1850);
DISPLAY INVISIBLE (1150 1850);
FORCEPROP 2 LAST PATH I7
J 0
(750 2000);
DISPLAY 1.021277 (750 2000);
DISPLAY INVISIBLE (750 2000);
FORCEADD Q_CAP..1
(7100 4600);
FORCEPROP 1 LAST LOCATION PC451
J 0
(7150 4725);
DISPLAY 0.489362 (7150 4725);
PAINT SKYBLUE (7150 4725);
FORCEPROP 0 LAST $SEC 1
J 0
(7150 4775);
DISPLAY 0.680851 (7150 4775);
PAINT MONO (7150 4775);
DISPLAY INVISIBLE (7150 4775);
FORCEPROP 0 LAST CDS_SEC 1
J 0
(7150 4775);
DISPLAY 1.021277 (7150 4775);
DISPLAY INVISIBLE (7150 4775);
FORCEPROP 1 LASTPIN (7100 4700) $PN 1
J 0
(7110 4680);
DISPLAY 0.489362 (7110 4680);
PAINT MONO (7110 4680);
FORCEPROP 1 LASTPIN (7100 4500) $PN 2
J 0
(7110 4480);
DISPLAY 0.489362 (7110 4480);
PAINT MONO (7110 4480);
FORCEPROP 1 LAST MATERIAL X7R
J 0
(7150 4525);
DISPLAY 0.489362 (7150 4525);
PAINT SKYBLUE (7150 4525);
FORCEPROP 1 LAST TOLERANCE 10%
J 0
(7150 4575);
DISPLAY 0.489362 (7150 4575);
PAINT SKYBLUE (7150 4575);
FORCEPROP 1 LAST VALUE 100NF
J 0
(7150 4675);
DISPLAY 0.489362 (7150 4675);
PAINT SKYBLUE (7150 4675);
FORCEPROP 1 LAST PART_NUMBER CH4106K1B01
J 0
(7150 4425);
DISPLAY 0.489362 (7150 4425);
PAINT SKYBLUE (7150 4425);
FORCEPROP 1 LAST VOLTAGE 50V
J 0
(7150 4625);
DISPLAY 0.489362 (7150 4625);
PAINT SKYBLUE (7150 4625);
FORCEPROP 1 LAST PACK_TYPE C0402
J 0
(7150 4475);
DISPLAY 0.489362 (7150 4475);
PAINT SKYBLUE (7150 4475);
FORCEPROP 2 LAST CDS_LIB pure_quanta
J 0
(7100 4600);
DISPLAY INVISIBLE (7100 4600);
FORCEPROP 1 LAST PATH I70
J 0
(7150 4750);
DISPLAY 0.978723 (7150 4750);
PAINT WHITE (7150 4750);
DISPLAY INVISIBLE (7150 4750);
FORCEADD VCC_CORE..1
(5650 6075);
FORCEPROP 3 LASTPIN (5650 6025) SIG_NAME P12V_STBY\g
J 0
(5660 6035);
DISPLAY 0.659574 (5660 6035);
PAINT MONO (5660 6035);
DISPLAY INVISIBLE (5660 6035);
FORCEPROP 1 LAST HDL_POWER P12V_STBY
J 1
(5650 6125);
DISPLAY 0.489362 (5650 6125);
PAINT GREEN (5650 6125);
FORCEPROP 2 LAST CDS_LIB pure_quanta_power
J 0
(5650 6075);
DISPLAY INVISIBLE (5650 6075);
FORCEPROP 1 LAST PATH I71
J 0
(5700 6100);
DISPLAY 0.872340 (5700 6100);
PAINT AQUA (5700 6100);
DISPLAY INVISIBLE (5700 6100);
FORCEADD Q_CAP..1
(7425 4600);
FORCEPROP 1 LAST LOCATION PC456_1
J 0
(7475 4725);
DISPLAY 0.489362 (7475 4725);
PAINT SKYBLUE (7475 4725);
FORCEPROP 0 LAST $SEC 1
J 0
(7475 4775);
DISPLAY 0.680851 (7475 4775);
PAINT MONO (7475 4775);
DISPLAY INVISIBLE (7475 4775);
FORCEPROP 0 LAST CDS_SEC 1
J 0
(7475 4775);
DISPLAY 1.021277 (7475 4775);
DISPLAY INVISIBLE (7475 4775);
FORCEPROP 1 LASTPIN (7425 4700) $PN 1
J 0
(7435 4680);
DISPLAY 0.489362 (7435 4680);
PAINT MONO (7435 4680);
FORCEPROP 1 LASTPIN (7425 4500) $PN 2
J 0
(7435 4480);
DISPLAY 0.489362 (7435 4480);
PAINT MONO (7435 4480);
FORCEPROP 1 LAST MATERIAL X6S
J 0
(7475 4525);
DISPLAY 0.489362 (7475 4525);
PAINT SKYBLUE (7475 4525);
FORCEPROP 1 LAST TOLERANCE 20%
J 0
(7475 4575);
DISPLAY 0.489362 (7475 4575);
PAINT SKYBLUE (7475 4575);
FORCEPROP 1 LAST VALUE 22UF
J 0
(7475 4675);
DISPLAY 0.489362 (7475 4675);
PAINT SKYBLUE (7475 4675);
FORCEPROP 1 LAST PART_NUMBER TMP_QCH622KMEA01
J 0
(7475 4425);
DISPLAY 0.489362 (7475 4425);
PAINT SKYBLUE (7475 4425);
FORCEPROP 1 LAST VOLTAGE 4V
J 0
(7475 4625);
DISPLAY 0.489362 (7475 4625);
PAINT SKYBLUE (7475 4625);
FORCEPROP 1 LAST PACK_TYPE 0805
J 0
(7475 4475);
DISPLAY 0.489362 (7475 4475);
PAINT SKYBLUE (7475 4475);
FORCEPROP 2 LAST CDS_LIB pure_quanta
J 0
(7425 4600);
DISPLAY INVISIBLE (7425 4600);
FORCEPROP 1 LAST PATH I72
J 0
(7475 4750);
DISPLAY 0.978723 (7475 4750);
PAINT WHITE (7475 4750);
DISPLAY INVISIBLE (7475 4750);
FORCEADD Q_CAP..1
(7875 4600);
FORCEPROP 1 LAST LOCATION PC459_1
J 0
(7925 4725);
DISPLAY 0.489362 (7925 4725);
PAINT SKYBLUE (7925 4725);
FORCEPROP 0 LAST $SEC 1
J 0
(7925 4775);
DISPLAY 0.680851 (7925 4775);
PAINT MONO (7925 4775);
DISPLAY INVISIBLE (7925 4775);
FORCEPROP 0 LAST CDS_SEC 1
J 0
(7925 4775);
DISPLAY 1.021277 (7925 4775);
DISPLAY INVISIBLE (7925 4775);
FORCEPROP 1 LASTPIN (7875 4700) $PN 1
J 0
(7885 4680);
DISPLAY 0.489362 (7885 4680);
PAINT MONO (7885 4680);
FORCEPROP 1 LASTPIN (7875 4500) $PN 2
J 0
(7885 4480);
DISPLAY 0.489362 (7885 4480);
PAINT MONO (7885 4480);
FORCEPROP 1 LAST MATERIAL X6S
J 0
(7925 4525);
DISPLAY 0.489362 (7925 4525);
PAINT SKYBLUE (7925 4525);
FORCEPROP 1 LAST TOLERANCE 20%
J 0
(7925 4575);
DISPLAY 0.489362 (7925 4575);
PAINT SKYBLUE (7925 4575);
FORCEPROP 1 LAST VALUE 22UF
J 0
(7925 4675);
DISPLAY 0.489362 (7925 4675);
PAINT SKYBLUE (7925 4675);
FORCEPROP 1 LAST VOLTAGE 4V
J 0
(7925 4625);
DISPLAY 0.489362 (7925 4625);
PAINT SKYBLUE (7925 4625);
FORCEPROP 1 LAST PACK_TYPE 0805
J 0
(7925 4475);
DISPLAY 0.489362 (7925 4475);
PAINT SKYBLUE (7925 4475);
FORCEPROP 2 LAST CDS_LIB pure_quanta
J 0
(7875 4600);
DISPLAY INVISIBLE (7875 4600);
FORCEPROP 1 LAST PATH I73
J 0
(7925 4750);
DISPLAY 0.978723 (7925 4750);
PAINT WHITE (7925 4750);
DISPLAY INVISIBLE (7925 4750);
FORCEPROP 1 LAST PART_NUMBER TMP_QCH622KMEA01
J 0
(7925 4425);
DISPLAY 0.489362 (7925 4425);
PAINT SKYBLUE (7925 4425);
DISPLAY INVISIBLE (7925 4425);
FORCEADD Q_INDUCTOR..1
(5375 5975);
FORCEPROP 1 LAST LOCATION PL49
J 0
(5225 6150);
DISPLAY 0.489362 (5225 6150);
PAINT SKYBLUE (5225 6150);
FORCEPROP 2 LAST $SEC 1
J 0
(5450 6075);
DISPLAY 0.680851 (5450 6075);
PAINT MONO (5450 6075);
DISPLAY INVISIBLE (5450 6075);
FORCEPROP 2 LAST CDS_SEC 1
J 0
(5450 6075);
DISPLAY 1.021277 (5450 6075);
DISPLAY INVISIBLE (5450 6075);
FORCEPROP 2 LASTPIN (5275 5950) $PN 1
J 2
(5265 5960);
DISPLAY 0.489362 (5265 5960);
FORCEPROP 2 LASTPIN (5475 5950) $PN 2
J 0
(5485 5960);
DISPLAY 0.489362 (5485 5960);
FORCEPROP 1 LAST MATERIAL IND
J 0
(5225 6100);
DISPLAY 0.489362 (5225 6100);
PAINT SKYBLUE (5225 6100);
FORCEPROP 2 LAST VALUE 50NH/86A
J 0
(5225 6250);
DISPLAY 0.489362 (5225 6250);
PAINT SKYBLUE (5225 6250);
FORCEPROP 1 LAST PART_NUMBER CVA50^0MZ09
J 0
(5225 6050);
DISPLAY 0.489362 (5225 6050);
PAINT SKYBLUE (5225 6050);
FORCEPROP 2 LAST PACK_TYPE SMLF
J 0
(5225 6200);
DISPLAY 0.489362 (5225 6200);
PAINT SKYBLUE (5225 6200);
FORCEPROP 1 LAST NEEDS_NO_SIZE TRUE
J 0
(5375 5975);
DISPLAY 0.468085 (5375 5975);
PAINT GREEN (5375 5975);
DISPLAY INVISIBLE (5375 5975);
FORCEPROP 2 LAST CDS_LIB pure_quanta
J 0
(5375 5975);
PAINT MONO (5375 5975);
DISPLAY INVISIBLE (5375 5975);
FORCEPROP 1 LAST PATH I74
J 0
(5450 6030);
DISPLAY 0.723404 (5450 6030);
PAINT GREEN (5450 6030);
DISPLAY INVISIBLE (5450 6030);
FORCEADD UNIVERSAL_GND..1
(8175 4250);
FORCEPROP 3 LASTPIN (8175 4300) SIG_NAME GND\g
J 0
(8185 4310);
DISPLAY 0.659574 (8185 4310);
PAINT MONO (8185 4310);
DISPLAY INVISIBLE (8185 4310);
FORCEPROP 2 LAST CDS_LIB pure_quanta_power
J 0
(8175 4250);
PAINT MONO (8175 4250);
DISPLAY INVISIBLE (8175 4250);
FORCEPROP 1 LAST PATH I75
J 0
(8250 4250);
DISPLAY 0.872340 (8250 4250);
PAINT AQUA (8250 4250);
DISPLAY INVISIBLE (8250 4250);
FORCEPROP 1 LAST HDL_POWER GND
J 1
(8200 4175);
DISPLAY 0.872340 (8200 4175);
PAINT GREEN (8200 4175);
DISPLAY INVISIBLE (8200 4175);
FORCEADD VCC_CORE..1
(8175 4900);
FORCEPROP 3 LASTPIN (8175 4850) SIG_NAME PVDDIO_P1\g
J 0
(8185 4860);
DISPLAY 0.659574 (8185 4860);
PAINT MONO (8185 4860);
DISPLAY INVISIBLE (8185 4860);
FORCEPROP 1 LAST HDL_POWER PVDDIO_P1
J 1
(8175 4950);
DISPLAY 0.489362 (8175 4950);
PAINT GREEN (8175 4950);
FORCEPROP 2 LAST CDS_LIB pure_quanta_power
J 0
(8175 4900);
DISPLAY INVISIBLE (8175 4900);
FORCEPROP 1 LAST PATH I76
J 0
(8225 4925);
DISPLAY 0.872340 (8225 4925);
PAINT AQUA (8225 4925);
DISPLAY INVISIBLE (8225 4925);
FORCEADD UNIVERSAL_GND..1
(7825 1500);
FORCEPROP 3 LASTPIN (7825 1550) SIG_NAME GND\g
J 0
(7835 1560);
DISPLAY 0.659574 (7835 1560);
PAINT MONO (7835 1560);
DISPLAY INVISIBLE (7835 1560);
FORCEPROP 2 LAST CDS_LIB pure_quanta_power
J 0
(7825 1500);
PAINT MONO (7825 1500);
DISPLAY INVISIBLE (7825 1500);
FORCEPROP 1 LAST PATH I80
J 0
(7900 1500);
DISPLAY 0.872340 (7900 1500);
PAINT AQUA (7900 1500);
DISPLAY INVISIBLE (7900 1500);
FORCEPROP 1 LAST HDL_POWER GND
J 1
(7850 1425);
DISPLAY 0.872340 (7850 1425);
PAINT GREEN (7850 1425);
DISPLAY INVISIBLE (7850 1425);
FORCEADD Q_CAP..1
(4650 5725);
FORCEPROP 1 LAST LOCATION PC448_1
J 0
(4700 5825);
DISPLAY 0.489362 (4700 5825);
PAINT SKYBLUE (4700 5825);
FORCEPROP 0 LAST $SEC 1
J 0
(4700 5875);
DISPLAY 0.680851 (4700 5875);
PAINT MONO (4700 5875);
DISPLAY INVISIBLE (4700 5875);
FORCEPROP 0 LAST CDS_SEC 1
J 0
(4700 5875);
DISPLAY 1.021277 (4700 5875);
DISPLAY INVISIBLE (4700 5875);
FORCEPROP 1 LASTPIN (4650 5825) $PN 1
J 0
(4660 5805);
DISPLAY 0.489362 (4660 5805);
PAINT MONO (4660 5805);
FORCEPROP 1 LASTPIN (4650 5625) $PN 2
J 0
(4660 5605);
DISPLAY 0.489362 (4660 5605);
PAINT MONO (4660 5605);
FORCEPROP 1 LAST PART_NUMBER CH6104KEA00
J 0
(4700 5575);
DISPLAY 0.489362 (4700 5575);
PAINT SKYBLUE (4700 5575);
FORCEPROP 1 LAST MATERIAL X6S
J 0
(4700 5625);
DISPLAY 0.489362 (4700 5625);
PAINT SKYBLUE (4700 5625);
FORCEPROP 1 LAST TOLERANCE 10%
J 0
(4700 5675);
DISPLAY 0.489362 (4700 5675);
PAINT SKYBLUE (4700 5675);
FORCEPROP 1 LAST VALUE 10UF
J 0
(4700 5775);
DISPLAY 0.489362 (4700 5775);
PAINT SKYBLUE (4700 5775);
FORCEPROP 1 LAST VOLTAGE 25V
J 0
(4700 5725);
DISPLAY 0.489362 (4700 5725);
PAINT SKYBLUE (4700 5725);
FORCEPROP 1 LAST PACK_TYPE C0805
J 0
(4700 5525);
DISPLAY 0.489362 (4700 5525);
PAINT SKYBLUE (4700 5525);
FORCEPROP 2 LAST CDS_LIB pure_quanta
J 0
(4650 5725);
DISPLAY INVISIBLE (4650 5725);
FORCEPROP 1 LAST PATH I85
J 0
(4700 5875);
DISPLAY 0.978723 (4700 5875);
PAINT WHITE (4700 5875);
DISPLAY INVISIBLE (4700 5875);
FORCEADD Q_CAP..1
(5175 2975);
FORCEPROP 1 LAST LOCATION PC449_2
J 0
(5250 3125);
DISPLAY 0.489362 (5250 3125);
PAINT SKYBLUE (5250 3125);
FORCEPROP 0 LAST $SEC 1
J 0
(5225 3125);
DISPLAY 0.680851 (5225 3125);
PAINT MONO (5225 3125);
DISPLAY INVISIBLE (5225 3125);
FORCEPROP 0 LAST CDS_SEC 1
J 0
(5225 3125);
DISPLAY 1.021277 (5225 3125);
DISPLAY INVISIBLE (5225 3125);
FORCEPROP 1 LASTPIN (5175 3075) $PN 1
J 0
(5185 3055);
DISPLAY 0.489362 (5185 3055);
PAINT MONO (5185 3055);
FORCEPROP 1 LASTPIN (5175 2875) $PN 2
J 0
(5185 2855);
DISPLAY 0.489362 (5185 2855);
PAINT MONO (5185 2855);
FORCEPROP 1 LAST PART_NUMBER CH6104KEA00
J 0
(5250 2825);
DISPLAY 0.489362 (5250 2825);
PAINT SKYBLUE (5250 2825);
FORCEPROP 1 LAST MATERIAL X6S
J 0
(5250 2925);
DISPLAY 0.489362 (5250 2925);
PAINT SKYBLUE (5250 2925);
FORCEPROP 1 LAST TOLERANCE 10%
J 0
(5250 2975);
DISPLAY 0.489362 (5250 2975);
PAINT SKYBLUE (5250 2975);
FORCEPROP 1 LAST VALUE 10UF
J 0
(5250 3075);
DISPLAY 0.489362 (5250 3075);
PAINT SKYBLUE (5250 3075);
FORCEPROP 1 LAST VOLTAGE 25V
J 0
(5250 3025);
DISPLAY 0.489362 (5250 3025);
PAINT SKYBLUE (5250 3025);
FORCEPROP 1 LAST PACK_TYPE C0805
J 0
(5250 2875);
DISPLAY 0.489362 (5250 2875);
PAINT SKYBLUE (5250 2875);
FORCEPROP 2 LAST CDS_LIB pure_quanta
J 0
(5175 2975);
DISPLAY INVISIBLE (5175 2975);
FORCEPROP 1 LAST PATH I86
J 0
(5225 3125);
DISPLAY 0.978723 (5225 3125);
PAINT WHITE (5225 3125);
DISPLAY INVISIBLE (5225 3125);
FORCEADD OFFPAGE..6
(5000 1800);
FORCEPROP 2 LAST $XR0 199 
J 0
(4690 1800);
DISPLAY 0.638298 (4690 1800);
PAINT MONO (4690 1800);
FORCEPROP 2 LAST CDS_LIB standard
J 0
(5000 1800);
DISPLAY INVISIBLE (5000 1800);
FORCEPROP 1 LAST OFFPAGE TRUE
J 0
(5325 1675);
DISPLAY 0.872340 (5325 1675);
PAINT GREEN (5325 1675);
DISPLAY INVISIBLE (5325 1675);
FORCEPROP 1 LAST COMMENT_BODY TRUE
J 0
(5100 1725);
DISPLAY 0.872340 (5100 1725);
PAINT GREEN (5100 1725);
DISPLAY INVISIBLE (5100 1725);
FORCEPROP 2 LAST PATH I99
J 0
(5050 1875);
DISPLAY 1.021277 (5050 1875);
DISPLAY INVISIBLE (5050 1875);
FORCEADD DNS..1
(550 1525);
PAINT RED (550 1525);
FORCEPROP 2 LAST CDS_LIB mstr_misc
J 0
(550 1525);
PAINT MONO (550 1525);
DISPLAY INVISIBLE (550 1525);
FORCEPROP 1 LAST COMMENT_BODY TRUE
R 1
J 0
(625 1300);
DISPLAY 0.872340 (625 1300);
PAINT GREEN (625 1300);
DISPLAY INVISIBLE (625 1300);
FORCEADD DNS..1
(3925 1350);
PAINT RED (3925 1350);
FORCEPROP 2 LAST CDS_LIB mstr_misc
J 0
(3925 1350);
DISPLAY INVISIBLE (3925 1350);
FORCEPROP 1 LAST COMMENT_BODY TRUE
R 1
J 0
(4000 1125);
DISPLAY 0.872340 (4000 1125);
PAINT GREEN (4000 1125);
DISPLAY INVISIBLE (4000 1125);
FORCEADD DNS..1
(7725 3050);
PAINT RED (7725 3050);
FORCEPROP 2 LAST CDS_LIB mstr_misc
J 0
(7725 3050);
DISPLAY INVISIBLE (7725 3050);
FORCEPROP 1 LAST COMMENT_BODY TRUE
R 1
J 0
(7800 2825);
DISPLAY 0.872340 (7800 2825);
PAINT GREEN (7800 2825);
DISPLAY INVISIBLE (7800 2825);
FORCEADD DNS..1
(4075 4575);
PAINT RED (4075 4575);
FORCEPROP 2 LAST CDS_LIB mstr_misc
J 0
(4075 4575);
DISPLAY INVISIBLE (4075 4575);
FORCEPROP 1 LAST COMMENT_BODY TRUE
R 1
J 0
(4150 4350);
DISPLAY 0.872340 (4150 4350);
PAINT GREEN (4150 4350);
DISPLAY INVISIBLE (4150 4350);
FORCEADD DNS..1
(3925 1850);
PAINT RED (3925 1850);
FORCEPROP 2 LAST CDS_LIB mstr_misc
J 0
(3925 1850);
DISPLAY INVISIBLE (3925 1850);
FORCEPROP 1 LAST COMMENT_BODY TRUE
R 1
J 0
(4000 1625);
DISPLAY 0.872340 (4000 1625);
PAINT GREEN (4000 1625);
DISPLAY INVISIBLE (4000 1625);
FORCEADD DNS..1
(575 4325);
PAINT RED (575 4325);
FORCEPROP 2 LAST CDS_LIB mstr_misc
J 0
(575 4325);
PAINT MONO (575 4325);
DISPLAY INVISIBLE (575 4325);
FORCEPROP 1 LAST COMMENT_BODY TRUE
R 1
J 0
(650 4100);
DISPLAY 0.872340 (650 4100);
PAINT GREEN (650 4100);
DISPLAY INVISIBLE (650 4100);
FORCEADD QUANTA_TITLE_BLOCK_C..1
(8900 -100);
FORCEPROP 0 LAST CDS_CON_LAST_MODIFIED Fri Mar 11 14:53:37 2022
J 0
(7015 -85);
DISPLAY INVISIBLE (7015 -85);
FORCEPROP 1 LAST CUSTOM_TXT_CDS <CON_LAST_MODIFIED>
J 0
(7015 -85);
DISPLAY 0.978723 (7015 -85);
FORCEPROP 2 LAST CUSTOM_TXT_CDS <XR_PAGE_TITLE>
J 0
(1010 5150);
DISPLAY 0.638298 (1010 5150);
PAINT PINK (1010 5150);
DISPLAY INVISIBLE (1010 5150);
FORCEPROP 1 LAST CUSTOM_TXT_CDS <NAME_2>
J 0
(5725 -50);
FORCEPROP 1 LAST CUSTOM_TXT_CDS <NAME_1>
J 0
(5725 75);
FORCEPROP 1 LAST CUSTOM_TXT_CDS <Q_NUMBER>
J 0
(7497 3);
DISPLAY 1.212766 (7497 3);
FORCEPROP 1 LAST CUSTOM_TXT_CDS <Q_PROJ>
J 0
(6518 2);
DISPLAY 1.212766 (6518 2);
FORCEPROP 1 LAST CUSTOM_TXT_CDS <Q_REV>
J 0
(8716 3);
DISPLAY 1.212766 (8716 3);
FORCEPROP 1 LAST CUSTOM_TXT_CDS <CON_PAGE_NUM> OF <CON_TOTAL_PAGES>
J 0
(8454 -82);
DISPLAY 0.978723 (8454 -82);
FORCEPROP 1 LAST Q_DEPT BU9
J 1
(5137 -51);
DISPLAY 1.957447 (5137 -51);
PAINT GREEN (5137 -51);
FORCEPROP 1 LAST Q_TITLE PVDDIO_P1 VR PHASE 1&2
J 0
(-400 -50);
DISPLAY 2.446809 (-400 -50);
PAINT GREEN (-400 -50);
FORCEPROP 2 LAST CDS_LIB pure_quanta
J 0
(8900 -100);
DISPLAY INVISIBLE (8900 -100);
FORCEPROP 1 LAST CDS_LMAN_SYM_OUTLINE -9475,6775,100,-125
J 0
(8900 -100);
DISPLAY 0.468085 (8900 -100);
PAINT GREEN (8900 -100);
DISPLAY INVISIBLE (8900 -100);
FORCEPROP 2 LAST PAGE_BORDER TRUE
J 0
(1010 5150);
DISPLAY 0.638298 (1010 5150);
PAINT PINK (1010 5150);
DISPLAY INVISIBLE (1010 5150);
FORCEPROP 1 LAST COMMENT_BODY TRUE
J 0
(8912 -113);
DISPLAY 0.978723 (8912 -113);
PAINT GREEN (8912 -113);
DISPLAY INVISIBLE (8912 -113);
FORCEPROP 2 LAST CDS_XR_PAGE_TITLE CR-198 : @T6G_MB_LIB.T6G(SCH_1):PAGE198
J 0
(1010 5150);
DISPLAY 0.638298 (1010 5150);
PAINT PINK (1010 5150);
DISPLAY INVISIBLE (1010 5150);
FORCEADD DNS..1
(4050 4075);
PAINT RED (4050 4075);
FORCEPROP 2 LAST CDS_LIB mstr_misc
J 0
(4050 4075);
DISPLAY INVISIBLE (4050 4075);
FORCEPROP 1 LAST COMMENT_BODY TRUE
R 1
J 0
(4125 3850);
DISPLAY 0.872340 (4125 3850);
PAINT GREEN (4125 3850);
DISPLAY INVISIBLE (4125 3850);
WIRE 16 -1 (550 1450)(550 1375);
WIRE 16 -1 (1000 4975)(1000 4925);
WIRE 16 -1 (1350 5550)(1350 5425);
WIRE 16 -1 (900 2350)(900 2300);
WIRE 16 -1 (1250 2925)(1250 2800);
WIRE 16 -1 (575 4250)(575 4175);
WIRE 16 -1 (25 4275)(25 4325);
WIRE 16 -1 (25 1525)(25 1575);
WIRE 16 -1 (4050 4000)(4050 3925);
WIRE 16 -1 (3950 1250)(3950 1175);
WIRE 16 -1 (5650 5950)(5650 6025);
WIRE 16 -1 (5475 5950)(5650 5950);
WIRE 16 -1 (1975 4625)(25 4625);
WIRE 16 -1 (1975 4700)(1975 4625);
FORCEPROP 0 LAST CDS_PHYS_NET_NAME PVCCIN_CPU0_VREF
J 0
(1975 4650);
PAINT MONO (1975 4650);
DISPLAY INVISIBLE (1975 4650);
WIRE 16 -1 (25 4625)(25 4525);
WIRE 16 -1 (1100 4700)(1975 4700);
FORCEPROP 2 LAST SIG_NAME PVDDCR_CPU1_P1_VCCS
J 0
(1165 4710);
DISPLAY 0.489362 (1165 4710);
WIRE 16 -1 (1975 4700)(2125 4700);
WIRE 16 -1 (2975 4900)(4925 4900);
FORCEPROP 2 LAST SIG_NAME SW_PVDDIO_P1_BOOTR1
J 0
(3165 4910);
DISPLAY 0.489362 (3165 4910);
FORCEPROP 2 LASTPROP $XRERR UNIQUE?
J 0
(2925 4910);
DISPLAY 0.638298 (2925 4910);
PAINT MONO (2925 4910);
DISPLAY INVISIBLE (2925 4910);
WIRE 16 -1 (4925 4900)(4925 4925);
WIRE 16 -1 (5375 4800)(4050 4800);
WIRE 16 -1 (4050 4800)(4050 4700);
WIRE 16 -1 (4050 4800)(2975 4800);
FORCEPROP 2 LAST SIG_NAME SW_PVDDIO_P1_SW1
J 0
(3165 4810);
DISPLAY 0.489362 (3165 4810);
FORCEPROP 2 LASTPROP $XRERR UNIQUE?
J 0
(2925 4810);
DISPLAY 0.638298 (2925 4810);
PAINT MONO (2925 4810);
DISPLAY INVISIBLE (2925 4810);
WIRE 16 -1 (2975 2150)(4575 2150);
FORCEPROP 2 LAST SIG_NAME SW_PVDDIO_P1_BOOTR2
J 0
(3165 2160);
DISPLAY 0.489362 (3165 2160);
FORCEPROP 2 LASTPROP $XRERR UNIQUE?
J 0
(2925 2160);
DISPLAY 0.638298 (2925 2160);
PAINT MONO (2925 2160);
DISPLAY INVISIBLE (2925 2160);
WIRE 16 -1 (4575 2150)(4575 2175);
WIRE 16 -1 (2975 2050)(3950 2050);
FORCEPROP 2 LAST SIG_NAME SW_PVDDIO_P1_SW2
J 0
(3165 2060);
DISPLAY 0.489362 (3165 2060);
FORCEPROP 2 LASTPROP $XRERR UNIQUE?
J 0
(2925 2060);
DISPLAY 0.638298 (2925 2060);
PAINT MONO (2925 2060);
DISPLAY INVISIBLE (2925 2060);
WIRE 16 -1 (3950 2050)(5550 2050);
WIRE 16 -1 (3950 1950)(3950 2050);
WIRE 16 -1 (7100 4500)(7100 4375);
WIRE 16 -1 (7425 4375)(7100 4375);
WIRE 16 -1 (7875 4375)(7425 4375);
WIRE 16 -1 (7425 4375)(7425 4500);
WIRE 16 -1 (8175 4375)(7875 4375);
WIRE 16 -1 (7875 4500)(7875 4375);
WIRE 16 -1 (8175 4500)(8175 4375);
WIRE 16 -1 (8175 4300)(8175 4375);
WIRE 16 -1 (6700 4475)(6700 4550);
WIRE 16 -1 (6175 4550)(6700 4550);
WIRE 16 -1 (6900 4800)(6900 3800);
WIRE 16 -1 (7100 4800)(6900 4800);
WIRE 16 -1 (6900 4800)(6175 4800);
WIRE 16 -1 (6900 3800)(5200 3800);
WIRE 16 -1 (7425 4800)(7100 4800);
WIRE 16 -1 (7100 4700)(7100 4800);
WIRE 16 -1 (7875 4800)(7425 4800);
WIRE 16 -1 (7425 4800)(7425 4700);
WIRE 16 -1 (8175 4800)(7875 4800);
WIRE 16 -1 (7875 4700)(7875 4800);
WIRE 16 -1 (8175 4850)(8175 4800);
WIRE 16 -1 (8175 4800)(8175 4700);
WIRE 16 -1 (6925 3175)(6925 3300);
WIRE 16 -1 (6925 3300)(7325 3300);
WIRE 16 -1 (7325 3300)(7725 3300);
WIRE 16 -1 (7325 3175)(7325 3300);
WIRE 16 -1 (7725 3350)(7725 3300);
WIRE 16 -1 (7725 3300)(7725 3175);
WIRE 16 -1 (7050 1025)(7050 2050);
WIRE 16 -1 (7050 1025)(5025 1025);
WIRE 16 -1 (7400 2050)(7050 2050);
WIRE 16 -1 (6350 2050)(7050 2050);
WIRE 16 -1 (7400 2050)(7825 2050);
WIRE 16 -1 (7400 2050)(7400 1950);
WIRE 16 -1 (7825 2150)(7825 2050);
WIRE 16 -1 (7825 1950)(7825 2050);
WIRE 16 -1 (7825 1625)(7400 1625);
WIRE 16 -1 (7825 1550)(7825 1625);
WIRE 16 -1 (7825 1750)(7825 1625);
WIRE 16 -1 (7400 1625)(7400 1750);
WIRE 16 -1 (6350 1800)(6775 1800);
FORCEPROP 2 LAST SIG_NAME IND_PVDDIO_P1_CPL2
J 0
(6390 1810);
DISPLAY 0.489362 (6390 1810);
WIRE 16 -1 (3950 2400)(4575 2400);
FORCEPROP 2 LAST SIG_NAME SW_PVDDIO_P1_BOOT2_R
J 0
(4165 2435);
DISPLAY 0.489362 (4165 2435);
FORCEPROP 2 LASTPROP $XRERR UNIQUE?
J 0
(3925 2435);
DISPLAY 0.638298 (3925 2435);
PAINT MONO (3925 2435);
DISPLAY INVISIBLE (3925 2435);
WIRE 16 -1 (4575 2400)(4575 2375);
WIRE 16 -1 (5050 1800)(5550 1800);
FORCEPROP 2 LAST SIG_NAME IND_PVDDIO_P1_CPL3
J 0
(5065 1810);
DISPLAY 0.489362 (5065 1810);
WIRE 16 -1 (4050 4500)(4050 4200);
FORCEPROP 2 LAST SIG_NAME SW_PVDDIO_P1_SW1_RC
J 0
(4090 4310);
DISPLAY 0.489362 (4090 4310);
FORCEPROP 2 LASTPROP $XRERR UNIQUE?
J 0
(3850 4310);
DISPLAY 0.638298 (3850 4310);
PAINT MONO (3850 4310);
DISPLAY INVISIBLE (3850 4310);
WIRE 16 -1 (3225 4250)(3225 4200);
WIRE 16 -1 (2975 4250)(3225 4250);
WIRE 16 -1 (3225 4300)(3225 4250);
WIRE 16 -1 (3225 4200)(3225 4125);
WIRE 16 -1 (2975 4200)(3225 4200);
WIRE 16 -1 (3225 4300)(3225 4350);
WIRE 16 -1 (2975 4300)(3225 4300);
WIRE 16 -1 (3225 4350)(2975 4350);
WIRE 16 -1 (2975 4550)(3800 4550);
FORCEPROP 2 LAST SIG_NAME PVDDIO_P1_VOS1
J 0
(3090 4575);
DISPLAY 0.489362 (3090 4575);
FORCEPROP 2 LASTPROP $XRERR UNIQUE?
J 0
(2850 4575);
DISPLAY 0.638298 (2850 4575);
PAINT MONO (2850 4575);
DISPLAY INVISIBLE (2850 4575);
WIRE 16 -1 (3800 4550)(3800 3800);
WIRE 16 -1 (5000 3800)(3800 3800);
WIRE 16 -1 (2975 5150)(3800 5150);
FORCEPROP 2 LAST SIG_NAME SW_PVDDIO_P1_BOOT1
J 0
(3165 5160);
DISPLAY 0.489362 (3165 5160);
FORCEPROP 2 LASTPROP $XRERR UNIQUE?
J 0
(2925 5160);
DISPLAY 0.638298 (2925 5160);
PAINT MONO (2925 5160);
DISPLAY INVISIBLE (2925 5160);
WIRE 16 -1 (3550 4450)(2975 4450);
FORCEPROP 2 LAST SIG_NAME NC_PVDDIO_P1_GL2_1
J 0
(3090 4460);
DISPLAY 0.489362 (3090 4460);
FORCEPROP 2 LASTPROP $XRERR UNIQUE?
J 0
(3580 4450);
DISPLAY 0.638298 (3580 4450);
PAINT MONO (3580 4450);
DISPLAY INVISIBLE (3580 4450);
WIRE 16 -1 (2975 4500)(3550 4500);
FORCEPROP 2 LAST SIG_NAME NC_PVDDIO_P1_GL1_1
J 0
(3090 4510);
DISPLAY 0.489362 (3090 4510);
FORCEPROP 2 LASTPROP $XRERR UNIQUE?
J 0
(3580 4500);
DISPLAY 0.638298 (3580 4500);
PAINT MONO (3580 4500);
DISPLAY INVISIBLE (3580 4500);
WIRE 16 -1 (2125 4800)(1100 4800);
FORCEPROP 2 LAST SIG_NAME PVDDIO_P1_IMON1
J 0
(1165 4810);
DISPLAY 0.489362 (1165 4810);
WIRE 16 -1 (2125 4200)(1100 4200);
FORCEPROP 2 LAST SIG_NAME PVDDIO_P1_PWM1
J 0
(1165 4210);
DISPLAY 0.489362 (1165 4210);
WIRE 16 -1 (2125 4300)(1100 4300);
FORCEPROP 2 LAST SIG_NAME PVDDIO_P1_TEMP1
J 0
(1165 4310);
DISPLAY 0.489362 (1165 4310);
WIRE 16 -1 (2125 4550)(1700 4550);
FORCEPROP 2 LAST SIG_NAME NC_PVDDIO_P1_DNC1
J 0
(1680 4560);
DISPLAY 0.489362 (1680 4560);
FORCEPROP 2 LASTPROP $XRERR UNIQUE?
J 0
(1460 4550);
DISPLAY 0.638298 (1460 4550);
PAINT MONO (1460 4550);
DISPLAY INVISIBLE (1460 4550);
WIRE 16 -1 (575 4500)(2125 4500);
FORCEPROP 0 LAST CDS_PHYS_NET_NAME PVCCFA_EHV_FIVRA_CPU0_LSET1
J 0
(1165 4540);
PAINT MONO (1165 4540);
DISPLAY INVISIBLE (1165 4540);
FORCEPROP 2 LAST SIG_NAME PVDDIO_P1_LSET1
J 0
(1165 4510);
DISPLAY 0.489362 (1165 4510);
FORCEPROP 2 LASTPROP $XRERR UNIQUE?
J 0
(925 4510);
DISPLAY 0.638298 (925 4510);
PAINT MONO (925 4510);
DISPLAY INVISIBLE (925 4510);
WIRE 16 -1 (575 4500)(575 4450);
WIRE 16 -1 (1000 5250)(1575 5250);
WIRE 16 -1 (1000 5525)(1000 5250);
WIRE 16 -1 (1000 5250)(1000 5175);
WIRE 16 -1 (1575 5250)(1575 5150);
WIRE 16 -1 (1975 5150)(1575 5150);
FORCEPROP 0 LAST CDS_PHYS_NET_NAME PVCCFA_EHV_FIVRA_CPU0_VDD1
J 0
(1665 5190);
PAINT MONO (1665 5190);
DISPLAY INVISIBLE (1665 5190);
FORCEPROP 2 LAST SIG_NAME PVDDIO_P1_VCC1
J 0
(1640 5160);
DISPLAY 0.489362 (1640 5160);
FORCEPROP 2 LASTPROP $XRERR UNIQUE?
J 0
(1400 5160);
DISPLAY 0.638298 (1400 5160);
PAINT MONO (1400 5160);
DISPLAY INVISIBLE (1400 5160);
WIRE 16 -1 (2125 5150)(1975 5150);
WIRE 16 -1 (1975 5150)(1975 4950);
WIRE 16 -1 (2125 4950)(1975 4950);
WIRE 16 -1 (1000 5725)(1000 5850);
WIRE 16 -1 (1350 5850)(1000 5850);
WIRE 16 -1 (1000 5975)(1000 5850);
WIRE 16 -1 (1675 5850)(1350 5850);
WIRE 16 -1 (1350 5750)(1350 5850);
WIRE 16 -1 (1675 5450)(1675 5850);
WIRE 16 -1 (1675 5450)(2125 5450);
WIRE 16 -1 (3400 2875)(3400 2725);
WIRE 16 -1 (3400 2725)(3900 2725);
WIRE 16 -1 (4300 2725)(3900 2725);
WIRE 16 -1 (3900 2875)(3900 2725);
WIRE 16 -1 (4300 2725)(4700 2725);
WIRE 16 -1 (4300 2875)(4300 2725);
WIRE 16 -1 (5175 2725)(4700 2725);
WIRE 16 -1 (4700 2875)(4700 2725);
WIRE 16 -1 (5175 2875)(5175 2725);
WIRE 16 -1 (5175 2675)(5175 2725);
WIRE 16 -1 (2975 2400)(3750 2400);
FORCEPROP 2 LAST SIG_NAME SW_PVDDIO_P1_BOOT2
J 0
(3140 2410);
DISPLAY 0.489362 (3140 2410);
FORCEPROP 2 LASTPROP $XRERR UNIQUE?
J 0
(2900 2410);
DISPLAY 0.638298 (2900 2410);
PAINT MONO (2900 2410);
DISPLAY INVISIBLE (2900 2410);
WIRE 16 -1 (2975 1750)(3550 1750);
FORCEPROP 2 LAST SIG_NAME NC_PVDDIO_P1_GL1_2
J 0
(3165 1760);
DISPLAY 0.489362 (3165 1760);
FORCEPROP 2 LASTPROP $XRERR UNIQUE?
J 0
(3580 1750);
DISPLAY 0.638298 (3580 1750);
PAINT MONO (3580 1750);
DISPLAY INVISIBLE (3580 1750);
WIRE 16 -1 (2125 2050)(1075 2050);
FORCEPROP 2 LAST SIG_NAME PVDDIO_P1_IMON2
J 0
(1140 2060);
DISPLAY 0.489362 (1140 2060);
WIRE 16 -1 (1700 1800)(2125 1800);
FORCEPROP 2 LAST SIG_NAME NC_PVDDIO_P1_DNC2
J 0
(1630 1810);
DISPLAY 0.489362 (1630 1810);
FORCEPROP 2 LASTPROP $XRERR UNIQUE?
J 0
(1460 1800);
DISPLAY 0.638298 (1460 1800);
PAINT MONO (1460 1800);
DISPLAY INVISIBLE (1460 1800);
WIRE 16 -1 (900 2625)(1300 2625);
WIRE 16 -1 (900 2900)(900 2625);
WIRE 16 -1 (900 2625)(900 2550);
WIRE 16 -1 (1300 2625)(1300 2400);
WIRE 16 -1 (1975 2400)(1300 2400);
FORCEPROP 0 LAST CDS_PHYS_NET_NAME PVCCFA_EHV_FIVRA_CPU0_VDD2
J 0
(1365 2440);
PAINT MONO (1365 2440);
DISPLAY INVISIBLE (1365 2440);
FORCEPROP 2 LAST SIG_NAME PVDDIO_P1_VCC2
J 0
(1340 2410);
DISPLAY 0.489362 (1340 2410);
FORCEPROP 2 LASTPROP $XRERR UNIQUE?
J 0
(1100 2410);
DISPLAY 0.638298 (1100 2410);
PAINT MONO (1100 2410);
DISPLAY INVISIBLE (1100 2410);
WIRE 16 -1 (2125 2400)(1975 2400);
WIRE 16 -1 (1975 2400)(1975 2200);
WIRE 16 -1 (2125 2200)(1975 2200);
WIRE 16 -1 (900 3100)(900 3225);
WIRE 16 -1 (1250 3225)(900 3225);
WIRE 16 -1 (900 3350)(900 3225);
WIRE 16 -1 (1575 3225)(1250 3225);
WIRE 16 -1 (1250 3125)(1250 3225);
WIRE 16 -1 (1575 2700)(1575 3225);
WIRE 16 -1 (1575 2700)(2125 2700);
WIRE 16 -1 (1975 1875)(25 1875);
WIRE 16 -1 (1975 1950)(1975 1875);
FORCEPROP 0 LAST CDS_PHYS_NET_NAME PVCCIN_CPU0_VREF
J 0
(1975 1900);
PAINT MONO (1975 1900);
DISPLAY INVISIBLE (1975 1900);
WIRE 16 -1 (25 1875)(25 1775);
WIRE 16 -1 (1075 1950)(1975 1950);
FORCEPROP 2 LAST SIG_NAME PVDDCR_CPU1_P1_VCCS
J 0
(1140 1960);
DISPLAY 0.489362 (1140 1960);
WIRE 16 -1 (1975 1950)(2125 1950);
WIRE 16 -1 (4825 4550)(5375 4550);
FORCEPROP 2 LAST SIG_NAME IND_PVDDIO_P1_CPL2
J 0
(4890 4560);
DISPLAY 0.489362 (4890 4560);
WIRE 16 -1 (5000 5450)(5000 5625);
WIRE 16 -1 (4650 5450)(5000 5450);
WIRE 16 -1 (4650 5625)(4650 5450);
WIRE 16 -1 (4650 5450)(4575 5450);
WIRE 16 -1 (4575 5375)(4575 5450);
WIRE 16 -1 (4575 5450)(4300 5450);
WIRE 16 -1 (4300 5600)(4300 5450);
WIRE 16 -1 (4300 5450)(3975 5450);
WIRE 16 -1 (3975 5600)(3975 5450);
WIRE 16 -1 (3975 5450)(3650 5450);
WIRE 16 -1 (3650 5600)(3650 5450);
WIRE 16 -1 (3325 5450)(3650 5450);
WIRE 16 -1 (3325 5600)(3325 5450);
WIRE 16 -1 (3150 5450)(3150 5400);
WIRE 16 -1 (2975 5450)(3150 5450);
WIRE 16 -1 (3150 5950)(3150 5450);
WIRE 16 -1 (3150 5400)(2975 5400);
WIRE 16 -1 (3325 5950)(3150 5950);
WIRE 16 -1 (3325 5800)(3325 5950);
WIRE 16 -1 (3650 5950)(3325 5950);
WIRE 16 -1 (3975 5950)(3650 5950);
WIRE 16 -1 (3650 5800)(3650 5950);
WIRE 16 -1 (4300 5950)(3975 5950);
WIRE 16 -1 (3975 5950)(3975 5800);
WIRE 16 -1 (4575 5950)(4300 5950);
WIRE 16 -1 (4300 5800)(4300 5950);
WIRE 16 -1 (4650 5950)(4575 5950);
WIRE 16 -1 (4575 6000)(4575 5950);
WIRE 16 -1 (4650 5950)(5000 5950);
WIRE 16 -1 (4650 5950)(4650 5825);
WIRE 16 -1 (5000 5825)(5000 5950);
WIRE 16 -1 (5000 5950)(5275 5950);
WIRE 16 -1 (4000 5150)(4925 5150);
FORCEPROP 2 LAST SIG_NAME SW_PVDDIO_P1_BOOT1_R
J 0
(4290 5160);
DISPLAY 0.489362 (4290 5160);
FORCEPROP 2 LASTPROP $XRERR UNIQUE?
J 0
(4050 5160);
DISPLAY 0.638298 (4050 5160);
PAINT MONO (4050 5160);
DISPLAY INVISIBLE (4050 5160);
WIRE 16 -1 (4925 5150)(4925 5125);
WIRE 16 -1 (7725 2975)(7725 2875);
WIRE 16 -1 (7725 2875)(7725 2775);
WIRE 16 -1 (7325 2875)(7725 2875);
WIRE 16 -1 (7325 2975)(7325 2875);
WIRE 16 -1 (6925 2875)(7325 2875);
WIRE 16 -1 (6925 2975)(6925 2875);
WIRE 16 -1 (3950 1750)(3950 1450);
FORCEPROP 2 LAST SIG_NAME SW_PVDDIO_P1_SW2_RC
J 0
(3990 1560);
DISPLAY 0.489362 (3990 1560);
FORCEPROP 2 LASTPROP $XRERR UNIQUE?
J 0
(3750 1560);
DISPLAY 0.638298 (3750 1560);
PAINT MONO (3750 1560);
DISPLAY INVISIBLE (3750 1560);
WIRE 16 -1 (2975 1700)(3550 1700);
FORCEPROP 2 LAST SIG_NAME NC_PVDDIO_P1_GL2_2
J 0
(3165 1710);
DISPLAY 0.489362 (3165 1710);
FORCEPROP 2 LASTPROP $XRERR UNIQUE?
J 0
(3580 1700);
DISPLAY 0.638298 (3580 1700);
PAINT MONO (3580 1700);
DISPLAY INVISIBLE (3580 1700);
WIRE 16 -1 (2975 1800)(3725 1800);
FORCEPROP 2 LAST SIG_NAME PVDDIO_P1_VOS2
J 0
(3165 1825);
DISPLAY 0.489362 (3165 1825);
FORCEPROP 2 LASTPROP $XRERR UNIQUE?
J 0
(2925 1825);
DISPLAY 0.638298 (2925 1825);
PAINT MONO (2925 1825);
DISPLAY INVISIBLE (2925 1825);
WIRE 16 -1 (3725 1800)(3725 1025);
WIRE 16 -1 (4825 1025)(3725 1025);
WIRE 16 -1 (3150 2700)(3150 2650);
WIRE 16 -1 (2975 2700)(3150 2700);
WIRE 16 -1 (3150 3225)(3150 2700);
WIRE 16 -1 (3150 2650)(2975 2650);
WIRE 16 -1 (3400 3225)(3150 3225);
WIRE 16 -1 (3400 3075)(3400 3225);
WIRE 16 -1 (3900 3225)(3400 3225);
WIRE 16 -1 (3900 3225)(4300 3225);
WIRE 16 -1 (3900 3075)(3900 3225);
WIRE 16 -1 (4300 3225)(4700 3225);
WIRE 16 -1 (4300 3225)(4300 3075);
WIRE 16 -1 (5175 3225)(4700 3225);
WIRE 16 -1 (4700 3075)(4700 3225);
WIRE 16 -1 (5175 3075)(5175 3225);
WIRE 16 -1 (5175 3300)(5175 3225);
WIRE 17 273 (6600 2625)(8100 2625);
WIRE 17 273 (6600 2625)(6600 3500);
WIRE 17 273 (8100 3500)(8100 2625);
WIRE 17 273 (6600 3500)(8100 3500);
WIRE 16 -1 (3225 1550)(3225 1600);
WIRE 16 -1 (2975 1550)(3225 1550);
WIRE 16 -1 (3225 1550)(3225 1500);
WIRE 16 -1 (3225 1600)(2975 1600);
WIRE 16 -1 (3225 1500)(3225 1450);
WIRE 16 -1 (2975 1500)(3225 1500);
WIRE 16 -1 (3225 1450)(3225 1375);
WIRE 16 -1 (2975 1450)(3225 1450);
WIRE 16 -1 (2125 1450)(1075 1450);
FORCEPROP 2 LAST SIG_NAME PVDDIO_P1_PWM2
J 0
(1140 1460);
DISPLAY 0.489362 (1140 1460);
WIRE 16 -1 (2125 1550)(1075 1550);
FORCEPROP 2 LAST SIG_NAME PVDDIO_P1_TEMP1
J 0
(1140 1560);
DISPLAY 0.489362 (1140 1560);
WIRE 16 -1 (550 1750)(2125 1750);
FORCEPROP 2 LAST SIG_NAME PVDDIO_P1_LSET2
J 0
(1140 1760);
DISPLAY 0.489362 (1140 1760);
FORCEPROP 2 LASTPROP $XRERR UNIQUE?
J 0
(900 1760);
DISPLAY 0.638298 (900 1760);
PAINT MONO (900 1760);
DISPLAY INVISIBLE (900 1760);
WIRE 16 -1 (550 1750)(550 1650);
DOT 1 (3225 4200);
DOT 1 (3225 4250);
DOT 1 (3225 4300);
DOT 1 (1000 5250);
DOT 1 (1000 5850);
DOT 1 (1350 5850);
DOT 1 (1975 4700);
DOT 1 (1975 5150);
DOT 1 (3150 5450);
DOT 1 (3650 5450);
DOT 1 (3325 5950);
DOT 1 (3650 5950);
DOT 1 (7425 4375);
DOT 1 (7875 4375);
DOT 1 (4050 4800);
DOT 1 (3975 5450);
DOT 1 (4300 5450);
DOT 1 (4575 5450);
DOT 1 (4650 5450);
DOT 1 (3975 5950);
DOT 1 (4300 5950);
DOT 1 (4575 5950);
DOT 1 (4650 5950);
DOT 1 (5000 5950);
DOT 1 (6900 4800);
DOT 1 (7100 4800);
DOT 1 (7425 4800);
DOT 1 (7875 4800);
DOT 1 (8175 4375);
DOT 1 (8175 4800);
DOT 1 (7825 2050);
DOT 1 (7825 1625);
DOT 1 (7400 2050);
DOT 1 (7050 2050);
DOT 1 (5175 3225);
DOT 1 (5175 2725);
DOT 1 (4700 3225);
DOT 1 (4700 2725);
DOT 1 (4300 3225);
DOT 1 (3900 3225);
DOT 1 (4300 2725);
DOT 1 (3900 2725);
DOT 1 (3400 3225);
DOT 1 (3150 2700);
DOT 1 (1975 2400);
DOT 1 (3225 1550);
DOT 1 (3225 1500);
DOT 1 (3225 1450);
DOT 1 (1975 1950);
DOT 1 (1250 3225);
DOT 1 (900 3225);
DOT 1 (900 2625);
DOT 1 (7725 3300);
DOT 1 (7725 2875);
DOT 1 (7325 3300);
DOT 1 (7325 2875);
DOT 1 (3950 2050);
FORCENOTE
PR275,PR274,PR369,PR368 = CS00002JB38
(-275 500) 0;
DISPLAY LEFT (-275 500);
DISPLAY 1.021277 (-275 500);
PAINT WHITE (-275 500);
FORCENOTE
PR372,PR373,PR278,PR279 = CS00002JB38
(-275 725) 0;
DISPLAY LEFT (-275 725);
DISPLAY 1.021277 (-275 725);
PAINT WHITE (-275 725);
FORCENOTE
PR278,PR279,PR372,PR373=CS00002JB38
(-275 75) 0;
DISPLAY LEFT (-275 75);
DISPLAY 1.021277 (-275 75);
PAINT WHITE (-275 75);
FORCENOTE
PR280,PR281,PR374,PR375=EMPTY
(-275 150) 0;
DISPLAY LEFT (-275 150);
DISPLAY 1.021277 (-275 150);
PAINT WHITE (-275 150);
FORCENOTE
PC435_7,PC436_8,PC620_9,PC621_10=EMPTY
(-275 225) 0;
DISPLAY LEFT (-275 225);
DISPLAY 1.021277 (-275 225);
PAINT WHITE (-275 225);
FORCENOTE
PU39,PU40,PU52,PU53=AL087000A02/MP87000GMJTH-C06A-Z
(-275 300) 0;
DISPLAY LEFT (-275 300);
DISPLAY 1.021277 (-275 300);
PAINT WHITE (-275 300);
FORCENOTE
3RD SOURCE:MPS BOM
(-275 375) 0;
DISPLAY LEFT (-275 375);
DISPLAY 1.021277 (-275 375);
PAINT WHITE (-275 375);
FORCENOTE
PR280,PR281,PR374,PR375 = EMPTY
(-275 650) 0;
DISPLAY LEFT (-275 650);
DISPLAY 1.021277 (-275 650);
PAINT WHITE (-275 650);
FORCENOTE
PC435_7,PC436_8,PC620_9,PC621_10 = EMPTY
(-275 575) 0;
DISPLAY LEFT (-275 575);
DISPLAY 1.021277 (-275 575);
PAINT WHITE (-275 575);
FORCENOTE
MAIN SOURCE:RENESAS BOM
(-275 1075) 0;
DISPLAY LEFT (-275 1075);
DISPLAY 1.021277 (-275 1075);
PAINT WHITE (-275 1075);
FORCENOTE
BOM NOTE
(-275 1175) 0;
DISPLAY LEFT (-275 1175);
DISPLAY 1.021277 (-275 1175);
PAINT WHITE (-275 1175);
FORCENOTE
PU39,PU40,PU52,PU53 = AL021590000/TDA21590
(-275 800) 0;
DISPLAY LEFT (-275 800);
DISPLAY 1.021277 (-275 800);
PAINT WHITE (-275 800);
FORCENOTE
PU39,PU40,PU52,PU53 =AL099390004/ISL99390FRZ-TR5935
(-275 1000) 0;
DISPLAY LEFT (-275 1000);
DISPLAY 1.021277 (-275 1000);
PAINT WHITE (-275 1000);
FORCENOTE
2ND=CH747LM8822
(7150 2675) 0;
DISPLAY LEFT (7150 2675);
DISPLAY 0.638298 (7150 2675);
PAINT WHITE (7150 2675);
FORCENOTE
2ND=CV+15^0TZ01
(6350 2125) 0;
DISPLAY LEFT (6350 2125);
DISPLAY 0.638298 (6350 2125);
PAINT WHITE (6350 2125);
FORCENOTE
DCR=2-3,0.27M OHM
(6350 2175) 0;
DISPLAY LEFT (6350 2175);
DISPLAY 0.638298 (6350 2175);
PAINT WHITE (6350 2175);
FORCENOTE
DCR=1-4,0.105M OHM
(6350 2225) 0;
DISPLAY LEFT (6350 2225);
DISPLAY 0.638298 (6350 2225);
PAINT WHITE (6350 2225);
FORCENOTE
11.0*7.5*12.5
(6350 2275) 0;
DISPLAY LEFT (6350 2275);
DISPLAY 0.638298 (6350 2275);
PAINT WHITE (6350 2275);
FORCENOTE
7.3*4.3*1.9
(7150 2725) 0;
DISPLAY LEFT (7150 2725);
DISPLAY 0.638298 (7150 2725);
PAINT WHITE (7150 2725);
FORCENOTE
3RD=CC72204MD03
(5050 5275) 0;
DISPLAY LEFT (5050 5275);
DISPLAY 0.638298 (5050 5275);
PAINT WHITE (5050 5275);
FORCENOTE
2ND=CC72204MD01
(5050 5325) 0;
DISPLAY LEFT (5050 5325);
DISPLAY 0.638298 (5050 5325);
PAINT WHITE (5050 5325);
FORCENOTE
8*11.5
(5050 5375) 0;
DISPLAY LEFT (5050 5375);
DISPLAY 0.638298 (5050 5375);
PAINT WHITE (5050 5375);
FORCENOTE
IRIPPLE:4.65A
(5050 5425) 0;
DISPLAY LEFT (5050 5425);
DISPLAY 0.638298 (5050 5425);
PAINT WHITE (5050 5425);
FORCENOTE
ESR=16M OHM
(5050 5475) 0;
DISPLAY LEFT (5050 5475);
DISPLAY 0.638298 (5050 5475);
PAINT WHITE (5050 5475);
FORCENOTE
3RD=CVA50^0MZ08
(5225 5625) 0;
DISPLAY LEFT (5225 5625);
DISPLAY 0.638298 (5225 5625);
PAINT WHITE (5225 5625);
FORCENOTE
2ND=CVA50^0MZ07
(5225 5675) 0;
DISPLAY LEFT (5225 5675);
DISPLAY 0.638298 (5225 5675);
PAINT WHITE (5225 5675);
FORCENOTE
DCR=0.09M OHM
(5225 5725) 0;
DISPLAY LEFT (5225 5725);
DISPLAY 0.638298 (5225 5725);
PAINT WHITE (5225 5725);
FORCENOTE
6.0*6.1*7.0
(5225 5775) 0;
DISPLAY LEFT (5225 5775);
DISPLAY 0.638298 (5225 5775);
PAINT WHITE (5225 5775);
FORCENOTE
ISAT:70A@100C
(5225 5825) 0;
DISPLAY LEFT (5225 5825);
DISPLAY 0.638298 (5225 5825);
PAINT WHITE (5225 5825);
FORCENOTE
PG2292.500HLT
(5225 5875) 0;
DISPLAY LEFT (5225 5875);
DISPLAY 0.638298 (5225 5875);
PAINT WHITE (5225 5875);
FORCENOTE
2ND SOURCE:INFENEON BOM
(-275 875) 0;
DISPLAY LEFT (-275 875);
DISPLAY 1.021277 (-275 875);
PAINT WHITE (-275 875);
FORCENOTE
PVDDIO_P1_PHASE1
(2275 5900) 0;
DISPLAY LEFT (2275 5900);
DISPLAY 1.021277 (2275 5900);
PAINT WHITE (2275 5900);
FORCENOTE
PVDDIO_P1_PHASE2
(2275 3125) 0;
DISPLAY LEFT (2275 3125);
DISPLAY 1.021277 (2275 3125);
PAINT WHITE (2275 3125);
FORCENOTE
ESR=4.5M OHM
(7150 2775) 0;
DISPLAY LEFT (7150 2775);
DISPLAY 0.638298 (7150 2775);
PAINT WHITE (7150 2775);
FORCENOTE
2ND=CV+15^0TZ01
(6175 4875) 0;
DISPLAY LEFT (6175 4875);
DISPLAY 0.638298 (6175 4875);
PAINT WHITE (6175 4875);
FORCENOTE
DCR=2-3,0.27M OHM
(6175 4925) 0;
DISPLAY LEFT (6175 4925);
DISPLAY 0.638298 (6175 4925);
PAINT WHITE (6175 4925);
FORCENOTE
DCR=1-4,0.105M OHM
(6175 4975) 0;
DISPLAY LEFT (6175 4975);
DISPLAY 0.638298 (6175 4975);
PAINT WHITE (6175 4975);
FORCENOTE
11.0*7.5*12.5
(6175 5025) 0;
DISPLAY LEFT (6175 5025);
DISPLAY 0.638298 (6175 5025);
PAINT WHITE (6175 5025);
FORCENOTE
PGL6303.151HLT
(6175 5125) 0;
DISPLAY LEFT (6175 5125);
DISPLAY 0.638298 (6175 5125);
PAINT WHITE (6175 5125);
FORCENOTE
ISAT:70A@100C
(6175 5075) 0;
DISPLAY LEFT (6175 5075);
DISPLAY 0.638298 (6175 5075);
PAINT WHITE (6175 5075);
FORCENOTE
PGL6303.151HLT
(6350 2375) 0;
DISPLAY LEFT (6350 2375);
DISPLAY 0.638298 (6350 2375);
PAINT WHITE (6350 2375);
FORCENOTE
ISAT:70A@100C
(6350 2325) 0;
DISPLAY LEFT (6350 2325);
DISPLAY 0.638298 (6350 2325);
PAINT WHITE (6350 2325);
QUIT
